G04 ================== begin FILE IDENTIFICATION RECORD ==================*
G04 Layout Name:  12432-1.brd*
G04 Film Name:    TSMD*
G04 File Format:  Gerber RS274X*
G04 File Origin:  Cadence Allegro 16.2-S037*
G04 Origin Date:  Wed Oct 17 10:59:52 2012*
G04 *
G04 Layer:  VIA CLASS/PASTEMASK_TOP*
G04 Layer:  PIN/PASTEMASK_TOP*
G04 Layer:  PACKAGE GEOMETRY/PASTEMASK_TOP*
G04 Layer:  DRAWING FORMAT/LAYER_PCB_STORY*
G04 Layer:  DRAWING FORMAT/LAYER_PAST_T*
G04 Layer:  BOARD GEOMETRY/PANEL_OUTLINE*
G04 *
G04 Offset:    (0.00 0.00)*
G04 Mirror:    No*
G04 Mode:      Positive*
G04 Rotation:  0*
G04 FullContactRelief:  No*
G04 UndefLineWidth:     6.00*
G04 ================== end FILE IDENTIFICATION RECORD ====================*
%FSLAX35Y35*MOIN*%
%IR0*IPPOS*OFA0.00000B0.00000*MIA0B0*SFA1.00000B1.00000*%
%AMMACRO63*
4,1,40,.013,.017,
-.013,.017,
-.013695,.016939,
-.014368,.016759,
-.015,.016464,
-.015571,.016064,
-.016064,.015571,
-.016464,.015,
-.016759,.014368,
-.016939,.013695,
-.017,.013,
-.017,-.013,
-.016939,-.013695,
-.016759,-.014368,
-.016464,-.015,
-.016064,-.015571,
-.015571,-.016064,
-.015,-.016464,
-.014368,-.016759,
-.013695,-.016939,
-.013,-.017,
.013,-.017,
.013695,-.016939,
.014368,-.016759,
.015,-.016464,
.015571,-.016064,
.016064,-.015571,
.016464,-.015,
.016759,-.014368,
.016939,-.013695,
.017,-.013,
.017,.013,
.016939,.013695,
.016759,.014368,
.016464,.015,
.016064,.015571,
.015571,.016064,
.015,.016464,
.014368,.016759,
.013695,.016939,
.013,.017,
0.0*
%
%ADD63MACRO63*%
%AMMACRO38*
4,1,40,.017,-.013,
.017,.013,
.016939,.013695,
.016759,.014368,
.016464,.015,
.016064,.015571,
.015571,.016064,
.015,.016464,
.014368,.016759,
.013695,.016939,
.013,.017,
-.013,.017,
-.013695,.016939,
-.014368,.016759,
-.015,.016464,
-.015571,.016064,
-.016064,.015571,
-.016464,.015,
-.016759,.014368,
-.016939,.013695,
-.017,.013,
-.017,-.013,
-.016939,-.013695,
-.016759,-.014368,
-.016464,-.015,
-.016064,-.015571,
-.015571,-.016064,
-.015,-.016464,
-.014368,-.016759,
-.013695,-.016939,
-.013,-.017,
.013,-.017,
.013695,-.016939,
.014368,-.016759,
.015,-.016464,
.015571,-.016064,
.016064,-.015571,
.016464,-.015,
.016759,-.014368,
.016939,-.013695,
.017,-.013,
0.0*
%
%ADD38MACRO38*%
%AMMACRO19*
4,1,3,.025,.0125,
0.0,-.0125,
-.025,.0125,
.025,.0125,
0.0*
%
%ADD19MACRO19*%
%ADD78R,.23X.032*%
%ADD51R,.045X.11*%
%ADD50R,.11X.045*%
%AMMACRO69*
4,1,3,.0125,0.0,
-.0125,-.025,
-.0125,.025,
.0125,0.0,
0.0*
%
%ADD69MACRO69*%
%ADD12R,.142X.028*%
%ADD33R,.208X.087*%
%ADD59R,.087X.208*%
%ADD10R,.05X.05*%
%ADD11C,.086*%
%AMMACRO53*
4,1,40,-.007,-.0225,
-.008389,-.022378,
-.009736,-.022018,
-.011,-.021428,
-.012142,-.020628,
-.013128,-.019642,
-.013928,-.0185,
-.014518,-.017236,
-.014878,-.015889,
-.015,-.0145,
-.015,.0145,
-.014878,.015889,
-.014518,.017236,
-.013928,.0185,
-.013128,.019642,
-.012142,.020628,
-.011,.021428,
-.009736,.022018,
-.008389,.022378,
-.007,.0225,
.007,.0225,
.008389,.022378,
.009736,.022018,
.011,.021428,
.012142,.020628,
.013128,.019642,
.013928,.0185,
.014518,.017236,
.014878,.015889,
.015,.0145,
.015,-.0145,
.014878,-.015889,
.014518,-.017236,
.013928,-.0185,
.013128,-.019642,
.012142,-.020628,
.011,-.021428,
.009736,-.022018,
.008389,-.022378,
.007,-.0225,
-.007,-.0225,
0.0*
%
%ADD53MACRO53*%
%AMMACRO25*
4,1,40,.011,-.007,
.011,.007,
.010939,.007695,
.010759,.008368,
.010464,.009,
.010064,.009571,
.009571,.010064,
.009,.010464,
.008368,.010759,
.007695,.010939,
.007,.011,
-.007,.011,
-.007695,.010939,
-.008368,.010759,
-.009,.010464,
-.009571,.010064,
-.010064,.009571,
-.010464,.009,
-.010759,.008368,
-.010939,.007695,
-.011,.007,
-.011,-.007,
-.010939,-.007695,
-.010759,-.008368,
-.010464,-.009,
-.010064,-.009571,
-.009571,-.010064,
-.009,-.010464,
-.008368,-.010759,
-.007695,-.010939,
-.007,-.011,
.007,-.011,
.007695,-.010939,
.008368,-.010759,
.009,-.010464,
.009571,-.010064,
.010064,-.009571,
.010464,-.009,
.010759,-.008368,
.010939,-.007695,
.011,-.007,
0.0*
%
%ADD25MACRO25*%
%AMMACRO17*
4,1,40,.007,.011,
-.007,.011,
-.007695,.010939,
-.008368,.010759,
-.009,.010464,
-.009571,.010064,
-.010064,.009571,
-.010464,.009,
-.010759,.008368,
-.010939,.007695,
-.011,.007,
-.011,-.007,
-.010939,-.007695,
-.010759,-.008368,
-.010464,-.009,
-.010064,-.009571,
-.009571,-.010064,
-.009,-.010464,
-.008368,-.010759,
-.007695,-.010939,
-.007,-.011,
.007,-.011,
.007695,-.010939,
.008368,-.010759,
.009,-.010464,
.009571,-.010064,
.010064,-.009571,
.010464,-.009,
.010759,-.008368,
.010939,-.007695,
.011,-.007,
.011,.007,
.010939,.007695,
.010759,.008368,
.010464,.009,
.010064,.009571,
.009571,.010064,
.009,.010464,
.008368,.010759,
.007695,.010939,
.007,.011,
0.0*
%
%ADD17MACRO17*%
%AMMACRO27*
4,1,40,-.012,.008,
-.012,-.008,
-.011939,-.008695,
-.011759,-.009368,
-.011464,-.01,
-.011064,-.010571,
-.010571,-.011064,
-.01,-.011464,
-.009368,-.011759,
-.008695,-.011939,
-.008,-.012,
.008,-.012,
.008695,-.011939,
.009368,-.011759,
.01,-.011464,
.010571,-.011064,
.011064,-.010571,
.011464,-.01,
.011759,-.009368,
.011939,-.008695,
.012,-.008,
.012,.008,
.011939,.008695,
.011759,.009368,
.011464,.01,
.011064,.010571,
.010571,.011064,
.01,.011464,
.009368,.011759,
.008695,.011939,
.008,.012,
-.008,.012,
-.008695,.011939,
-.009368,.011759,
-.01,.011464,
-.010571,.011064,
-.011064,.010571,
-.011464,.01,
-.011759,.009368,
-.011939,.008695,
-.012,.008,
0.0*
%
%ADD27MACRO27*%
%AMMACRO55*
4,1,40,.008,.012,
-.008,.012,
-.008695,.011939,
-.009368,.011759,
-.01,.011464,
-.010571,.011064,
-.011064,.010571,
-.011464,.01,
-.011759,.009368,
-.011939,.008695,
-.012,.008,
-.012,-.008,
-.011939,-.008695,
-.011759,-.009368,
-.011464,-.01,
-.011064,-.010571,
-.010571,-.011064,
-.01,-.011464,
-.009368,-.011759,
-.008695,-.011939,
-.008,-.012,
.008,-.012,
.008695,-.011939,
.009368,-.011759,
.01,-.011464,
.010571,-.011064,
.011064,-.010571,
.011464,-.01,
.011759,-.009368,
.011939,-.008695,
.012,-.008,
.012,.008,
.011939,.008695,
.011759,.009368,
.011464,.01,
.011064,.010571,
.010571,.011064,
.01,.011464,
.009368,.011759,
.008695,.011939,
.008,.012,
0.0*
%
%ADD55MACRO55*%
%AMMACRO67*
4,1,40,-.013,-.017,
.013,-.017,
.013695,-.016939,
.014368,-.016759,
.015,-.016464,
.015571,-.016064,
.016064,-.015571,
.016464,-.015,
.016759,-.014368,
.016939,-.013695,
.017,-.013,
.017,.013,
.016939,.013695,
.016759,.014368,
.016464,.015,
.016064,.015571,
.015571,.016064,
.015,.016464,
.014368,.016759,
.013695,.016939,
.013,.017,
-.013,.017,
-.013695,.016939,
-.014368,.016759,
-.015,.016464,
-.015571,.016064,
-.016064,.015571,
-.016464,.015,
-.016759,.014368,
-.016939,.013695,
-.017,.013,
-.017,-.013,
-.016939,-.013695,
-.016759,-.014368,
-.016464,-.015,
-.016064,-.015571,
-.015571,-.016064,
-.015,-.016464,
-.014368,-.016759,
-.013695,-.016939,
-.013,-.017,
0.0*
%
%ADD67MACRO67*%
%AMMACRO14*
4,1,40,-.017,.013,
-.017,-.013,
-.016939,-.013695,
-.016759,-.014368,
-.016464,-.015,
-.016064,-.015571,
-.015571,-.016064,
-.015,-.016464,
-.014368,-.016759,
-.013695,-.016939,
-.013,-.017,
.013,-.017,
.013695,-.016939,
.014368,-.016759,
.015,-.016464,
.015571,-.016064,
.016064,-.015571,
.016464,-.015,
.016759,-.014368,
.016939,-.013695,
.017,-.013,
.017,.013,
.016939,.013695,
.016759,.014368,
.016464,.015,
.016064,.015571,
.015571,.016064,
.015,.016464,
.014368,.016759,
.013695,.016939,
.013,.017,
-.013,.017,
-.013695,.016939,
-.014368,.016759,
-.015,.016464,
-.015571,.016064,
-.016064,.015571,
-.016464,.015,
-.016759,.014368,
-.016939,.013695,
-.017,.013,
0.0*
%
%ADD14MACRO14*%
%AMMACRO26*
4,1,40,.011,-.007,
.011,.007,
.010939,.007695,
.010759,.008368,
.010464,.009,
.010064,.009571,
.009571,.010064,
.009,.010464,
.008368,.010759,
.007695,.010939,
.007,.011,
-.007,.011,
-.007695,.010939,
-.008368,.010759,
-.009,.010464,
-.009571,.010064,
-.010064,.009571,
-.010464,.009,
-.010759,.008368,
-.010939,.007695,
-.011,.007,
-.011,-.007,
-.010939,-.007695,
-.010759,-.008368,
-.010464,-.009,
-.010064,-.009571,
-.009571,-.010064,
-.009,-.010464,
-.008368,-.010759,
-.007695,-.010939,
-.007,-.011,
.007,-.011,
.007695,-.010939,
.008368,-.010759,
.009,-.010464,
.009571,-.010064,
.010064,-.009571,
.010464,-.009,
.010759,-.008368,
.010939,-.007695,
.011,-.007,
0.0*
%
%ADD26MACRO26*%
%AMMACRO21*
4,1,40,.007,.011,
-.007,.011,
-.007695,.010939,
-.008368,.010759,
-.009,.010464,
-.009571,.010064,
-.010064,.009571,
-.010464,.009,
-.010759,.008368,
-.010939,.007695,
-.011,.007,
-.011,-.007,
-.010939,-.007695,
-.010759,-.008368,
-.010464,-.009,
-.010064,-.009571,
-.009571,-.010064,
-.009,-.010464,
-.008368,-.010759,
-.007695,-.010939,
-.007,-.011,
.007,-.011,
.007695,-.010939,
.008368,-.010759,
.009,-.010464,
.009571,-.010064,
.010064,-.009571,
.010464,-.009,
.010759,-.008368,
.010939,-.007695,
.011,-.007,
.011,.007,
.010939,.007695,
.010759,.008368,
.010464,.009,
.010064,.009571,
.009571,.010064,
.009,.010464,
.008368,.010759,
.007695,.010939,
.007,.011,
0.0*
%
%ADD21MACRO21*%
%AMMACRO64*
4,1,20,.0635,-.1075,
.049,-.1075,
.049,-.118,
.0395,-.118,
.0395,-.1075,
-.0395,-.1075,
-.0395,-.118,
-.049,-.118,
-.049,-.1075,
-.0635,-.1075,
-.0635,.1075,
-.049,.1075,
-.049,.118,
-.0395,.118,
-.0395,.1075,
.0395,.1075,
.0395,.118,
.049,.118,
.049,.1075,
.0635,.1075,
.0635,-.1075,
0.0*
%
%ADD64MACRO64*%
%AMMACRO16*
4,1,40,-.012,.008,
-.012,-.008,
-.011939,-.008695,
-.011759,-.009368,
-.011464,-.01,
-.011064,-.010571,
-.010571,-.011064,
-.01,-.011464,
-.009368,-.011759,
-.008695,-.011939,
-.008,-.012,
.008,-.012,
.008695,-.011939,
.009368,-.011759,
.01,-.011464,
.010571,-.011064,
.011064,-.010571,
.011464,-.01,
.011759,-.009368,
.011939,-.008695,
.012,-.008,
.012,.008,
.011939,.008695,
.011759,.009368,
.011464,.01,
.011064,.010571,
.010571,.011064,
.01,.011464,
.009368,.011759,
.008695,.011939,
.008,.012,
-.008,.012,
-.008695,.011939,
-.009368,.011759,
-.01,.011464,
-.010571,.011064,
-.011064,.010571,
-.011464,.01,
-.011759,.009368,
-.011939,.008695,
-.012,.008,
0.0*
%
%ADD16MACRO16*%
%AMMACRO54*
4,1,40,.008,.012,
-.008,.012,
-.008695,.011939,
-.009368,.011759,
-.01,.011464,
-.010571,.011064,
-.011064,.010571,
-.011464,.01,
-.011759,.009368,
-.011939,.008695,
-.012,.008,
-.012,-.008,
-.011939,-.008695,
-.011759,-.009368,
-.011464,-.01,
-.011064,-.010571,
-.010571,-.011064,
-.01,-.011464,
-.009368,-.011759,
-.008695,-.011939,
-.008,-.012,
.008,-.012,
.008695,-.011939,
.009368,-.011759,
.01,-.011464,
.010571,-.011064,
.011064,-.010571,
.011464,-.01,
.011759,-.009368,
.011939,-.008695,
.012,-.008,
.012,.008,
.011939,.008695,
.011759,.009368,
.011464,.01,
.011064,.010571,
.010571,.011064,
.01,.011464,
.009368,.011759,
.008695,.011939,
.008,.012,
0.0*
%
%ADD54MACRO54*%
%AMMACRO68*
4,1,40,-.013,-.017,
.013,-.017,
.013695,-.016939,
.014368,-.016759,
.015,-.016464,
.015571,-.016064,
.016064,-.015571,
.016464,-.015,
.016759,-.014368,
.016939,-.013695,
.017,-.013,
.017,.013,
.016939,.013695,
.016759,.014368,
.016464,.015,
.016064,.015571,
.015571,.016064,
.015,.016464,
.014368,.016759,
.013695,.016939,
.013,.017,
-.013,.017,
-.013695,.016939,
-.014368,.016759,
-.015,.016464,
-.015571,.016064,
-.016064,.015571,
-.016464,.015,
-.016759,.014368,
-.016939,.013695,
-.017,.013,
-.017,-.013,
-.016939,-.013695,
-.016759,-.014368,
-.016464,-.015,
-.016064,-.015571,
-.015571,-.016064,
-.015,-.016464,
-.014368,-.016759,
-.013695,-.016939,
-.013,-.017,
0.0*
%
%ADD68MACRO68*%
%AMMACRO15*
4,1,40,-.017,.013,
-.017,-.013,
-.016939,-.013695,
-.016759,-.014368,
-.016464,-.015,
-.016064,-.015571,
-.015571,-.016064,
-.015,-.016464,
-.014368,-.016759,
-.013695,-.016939,
-.013,-.017,
.013,-.017,
.013695,-.016939,
.014368,-.016759,
.015,-.016464,
.015571,-.016064,
.016064,-.015571,
.016464,-.015,
.016759,-.014368,
.016939,-.013695,
.017,-.013,
.017,.013,
.016939,.013695,
.016759,.014368,
.016464,.015,
.016064,.015571,
.015571,.016064,
.015,.016464,
.014368,.016759,
.013695,.016939,
.013,.017,
-.013,.017,
-.013695,.016939,
-.014368,.016759,
-.015,.016464,
-.015571,.016064,
-.016064,.015571,
-.016464,.015,
-.016759,.014368,
-.016939,.013695,
-.017,.013,
0.0*
%
%ADD15MACRO15*%
%AMMACRO70*
4,1,3,.0125,-.025,
-.0125,0.0,
.0125,.025,
.0125,-.025,
0.0*
%
%ADD70MACRO70*%
%ADD73R,.06X.012*%
%AMMACRO18*
4,1,3,0.0,.0125,
.025,-.0125,
-.025,-.0125,
0.0,.0125,
0.0*
%
%ADD18MACRO18*%
%ADD77R,.023X.04*%
%ADD74R,.06X.014*%
%ADD65R,.044X.012*%
%ADD48R,.04X.016*%
%ADD58R,.016X.04*%
%ADD56R,.014X.06*%
%ADD31R,.012X.044*%
%ADD22R,.045X.03*%
%ADD44R,.133X.128*%
%ADD57R,.128X.133*%
%ADD40R,.075X.02*%
%ADD75R,.05X.065*%
%ADD41R,.036X.024*%
%ADD34R,.065X.05*%
%ADD43R,.065X.025*%
%ADD61R,.025X.065*%
%ADD60R,.045X.055*%
%ADD49R,.048X.016*%
%ADD47R,.016X.048*%
%ADD32R,.055X.045*%
%ADD52R,.045X.075*%
%ADD46R,.054X.074*%
%ADD39R,.094X.026*%
%ADD72R,.075X.045*%
%ADD45R,.09X.095*%
%AMMACRO71*
4,1,40,-.0225,.007,
-.022378,.008389,
-.022018,.009736,
-.021428,.011,
-.020628,.012142,
-.019642,.013128,
-.0185,.013928,
-.017236,.014518,
-.015889,.014878,
-.0145,.015,
.0145,.015,
.015889,.014878,
.017236,.014518,
.0185,.013928,
.019642,.013128,
.020628,.012142,
.021428,.011,
.022018,.009736,
.022378,.008389,
.0225,.007,
.0225,-.007,
.022378,-.008389,
.022018,-.009736,
.021428,-.011,
.020628,-.012142,
.019642,-.013128,
.0185,-.013928,
.017236,-.014518,
.015889,-.014878,
.0145,-.015,
-.0145,-.015,
-.015889,-.014878,
-.017236,-.014518,
-.0185,-.013928,
-.019642,-.013128,
-.020628,-.012142,
-.021428,-.011,
-.022018,-.009736,
-.022378,-.008389,
-.0225,-.007,
-.0225,.007,
0.0*
%
%ADD71MACRO71*%
%AMMACRO66*
4,1,40,.007,.0225,
.008389,.022378,
.009736,.022018,
.011,.021428,
.012142,.020628,
.013128,.019642,
.013928,.0185,
.014518,.017236,
.014878,.015889,
.015,.0145,
.015,-.0145,
.014878,-.015889,
.014518,-.017236,
.013928,-.0185,
.013128,-.019642,
.012142,-.020628,
.011,-.021428,
.009736,-.022018,
.008389,-.022378,
.007,-.0225,
-.007,-.0225,
-.008389,-.022378,
-.009736,-.022018,
-.011,-.021428,
-.012142,-.020628,
-.013128,-.019642,
-.013928,-.0185,
-.014518,-.017236,
-.014878,-.015889,
-.015,-.0145,
-.015,.0145,
-.014878,.015889,
-.014518,.017236,
-.013928,.0185,
-.013128,.019642,
-.012142,.020628,
-.011,.021428,
-.009736,.022018,
-.008389,.022378,
-.007,.0225,
.007,.0225,
0.0*
%
%ADD66MACRO66*%
%ADD42R,.095X.09*%
%ADD76R,.089X.059*%
%AMMACRO36*
4,1,40,-.008,-.012,
.008,-.012,
.008695,-.011939,
.009368,-.011759,
.01,-.011464,
.010571,-.011064,
.011064,-.010571,
.011464,-.01,
.011759,-.009368,
.011939,-.008695,
.012,-.008,
.012,.008,
.011939,.008695,
.011759,.009368,
.011464,.01,
.011064,.010571,
.010571,.011064,
.01,.011464,
.009368,.011759,
.008695,.011939,
.008,.012,
-.008,.012,
-.008695,.011939,
-.009368,.011759,
-.01,.011464,
-.010571,.011064,
-.011064,.010571,
-.011464,.01,
-.011759,.009368,
-.011939,.008695,
-.012,.008,
-.012,-.008,
-.011939,-.008695,
-.011759,-.009368,
-.011464,-.01,
-.011064,-.010571,
-.010571,-.011064,
-.01,-.011464,
-.009368,-.011759,
-.008695,-.011939,
-.008,-.012,
0.0*
%
%ADD36MACRO36*%
%AMMACRO29*
4,1,40,.012,-.008,
.012,.008,
.011939,.008695,
.011759,.009368,
.011464,.01,
.011064,.010571,
.010571,.011064,
.01,.011464,
.009368,.011759,
.008695,.011939,
.008,.012,
-.008,.012,
-.008695,.011939,
-.009368,.011759,
-.01,.011464,
-.010571,.011064,
-.011064,.010571,
-.011464,.01,
-.011759,.009368,
-.011939,.008695,
-.012,.008,
-.012,-.008,
-.011939,-.008695,
-.011759,-.009368,
-.011464,-.01,
-.011064,-.010571,
-.010571,-.011064,
-.01,-.011464,
-.009368,-.011759,
-.008695,-.011939,
-.008,-.012,
.008,-.012,
.008695,-.011939,
.009368,-.011759,
.01,-.011464,
.010571,-.011064,
.011064,-.010571,
.011464,-.01,
.011759,-.009368,
.011939,-.008695,
.012,-.008,
0.0*
%
%ADD29MACRO29*%
%AMMACRO20*
4,1,40,-.007,-.011,
.007,-.011,
.007695,-.010939,
.008368,-.010759,
.009,-.010464,
.009571,-.010064,
.010064,-.009571,
.010464,-.009,
.010759,-.008368,
.010939,-.007695,
.011,-.007,
.011,.007,
.010939,.007695,
.010759,.008368,
.010464,.009,
.010064,.009571,
.009571,.010064,
.009,.010464,
.008368,.010759,
.007695,.010939,
.007,.011,
-.007,.011,
-.007695,.010939,
-.008368,.010759,
-.009,.010464,
-.009571,.010064,
-.010064,.009571,
-.010464,.009,
-.010759,.008368,
-.010939,.007695,
-.011,.007,
-.011,-.007,
-.010939,-.007695,
-.010759,-.008368,
-.010464,-.009,
-.010064,-.009571,
-.009571,-.010064,
-.009,-.010464,
-.008368,-.010759,
-.007695,-.010939,
-.007,-.011,
0.0*
%
%ADD20MACRO20*%
%AMMACRO23*
4,1,40,-.011,.007,
-.011,-.007,
-.010939,-.007695,
-.010759,-.008368,
-.010464,-.009,
-.010064,-.009571,
-.009571,-.010064,
-.009,-.010464,
-.008368,-.010759,
-.007695,-.010939,
-.007,-.011,
.007,-.011,
.007695,-.010939,
.008368,-.010759,
.009,-.010464,
.009571,-.010064,
.010064,-.009571,
.010464,-.009,
.010759,-.008368,
.010939,-.007695,
.011,-.007,
.011,.007,
.010939,.007695,
.010759,.008368,
.010464,.009,
.010064,.009571,
.009571,.010064,
.009,.010464,
.008368,.010759,
.007695,.010939,
.007,.011,
-.007,.011,
-.007695,.010939,
-.008368,.010759,
-.009,.010464,
-.009571,.010064,
-.010064,.009571,
-.010464,.009,
-.010759,.008368,
-.010939,.007695,
-.011,.007,
0.0*
%
%ADD23MACRO23*%
%AMMACRO62*
4,1,40,.013,.017,
-.013,.017,
-.013695,.016939,
-.014368,.016759,
-.015,.016464,
-.015571,.016064,
-.016064,.015571,
-.016464,.015,
-.016759,.014368,
-.016939,.013695,
-.017,.013,
-.017,-.013,
-.016939,-.013695,
-.016759,-.014368,
-.016464,-.015,
-.016064,-.015571,
-.015571,-.016064,
-.015,-.016464,
-.014368,-.016759,
-.013695,-.016939,
-.013,-.017,
.013,-.017,
.013695,-.016939,
.014368,-.016759,
.015,-.016464,
.015571,-.016064,
.016064,-.015571,
.016464,-.015,
.016759,-.014368,
.016939,-.013695,
.017,-.013,
.017,.013,
.016939,.013695,
.016759,.014368,
.016464,.015,
.016064,.015571,
.015571,.016064,
.015,.016464,
.014368,.016759,
.013695,.016939,
.013,.017,
0.0*
%
%ADD62MACRO62*%
%AMMACRO37*
4,1,40,.017,-.013,
.017,.013,
.016939,.013695,
.016759,.014368,
.016464,.015,
.016064,.015571,
.015571,.016064,
.015,.016464,
.014368,.016759,
.013695,.016939,
.013,.017,
-.013,.017,
-.013695,.016939,
-.014368,.016759,
-.015,.016464,
-.015571,.016064,
-.016064,.015571,
-.016464,.015,
-.016759,.014368,
-.016939,.013695,
-.017,.013,
-.017,-.013,
-.016939,-.013695,
-.016759,-.014368,
-.016464,-.015,
-.016064,-.015571,
-.015571,-.016064,
-.015,-.016464,
-.014368,-.016759,
-.013695,-.016939,
-.013,-.017,
.013,-.017,
.013695,-.016939,
.014368,-.016759,
.015,-.016464,
.015571,-.016064,
.016064,-.015571,
.016464,-.015,
.016759,-.014368,
.016939,-.013695,
.017,-.013,
0.0*
%
%ADD37MACRO37*%
%AMMACRO30*
4,1,20,.1075,.0635,
.1075,.049,
.118,.049,
.118,.0395,
.1075,.0395,
.1075,-.0395,
.118,-.0395,
.118,-.049,
.1075,-.049,
.1075,-.0635,
-.1075,-.0635,
-.1075,-.049,
-.118,-.049,
-.118,-.0395,
-.1075,-.0395,
-.1075,.0395,
-.118,.0395,
-.118,.049,
-.1075,.049,
-.1075,.0635,
.1075,.0635,
0.0*
%
%ADD30MACRO30*%
%AMMACRO35*
4,1,40,-.008,-.012,
.008,-.012,
.008695,-.011939,
.009368,-.011759,
.01,-.011464,
.010571,-.011064,
.011064,-.010571,
.011464,-.01,
.011759,-.009368,
.011939,-.008695,
.012,-.008,
.012,.008,
.011939,.008695,
.011759,.009368,
.011464,.01,
.011064,.010571,
.010571,.011064,
.01,.011464,
.009368,.011759,
.008695,.011939,
.008,.012,
-.008,.012,
-.008695,.011939,
-.009368,.011759,
-.01,.011464,
-.010571,.011064,
-.011064,.010571,
-.011464,.01,
-.011759,.009368,
-.011939,.008695,
-.012,.008,
-.012,-.008,
-.011939,-.008695,
-.011759,-.009368,
-.011464,-.01,
-.011064,-.010571,
-.010571,-.011064,
-.01,-.011464,
-.009368,-.011759,
-.008695,-.011939,
-.008,-.012,
0.0*
%
%ADD35MACRO35*%
%AMMACRO28*
4,1,40,.012,-.008,
.012,.008,
.011939,.008695,
.011759,.009368,
.011464,.01,
.011064,.010571,
.010571,.011064,
.01,.011464,
.009368,.011759,
.008695,.011939,
.008,.012,
-.008,.012,
-.008695,.011939,
-.009368,.011759,
-.01,.011464,
-.010571,.011064,
-.011064,.010571,
-.011464,.01,
-.011759,.009368,
-.011939,.008695,
-.012,.008,
-.012,-.008,
-.011939,-.008695,
-.011759,-.009368,
-.011464,-.01,
-.011064,-.010571,
-.010571,-.011064,
-.01,-.011464,
-.009368,-.011759,
-.008695,-.011939,
-.008,-.012,
.008,-.012,
.008695,-.011939,
.009368,-.011759,
.01,-.011464,
.010571,-.011064,
.011064,-.010571,
.011464,-.01,
.011759,-.009368,
.011939,-.008695,
.012,-.008,
0.0*
%
%ADD28MACRO28*%
%AMMACRO13*
4,1,40,-.007,-.011,
.007,-.011,
.007695,-.010939,
.008368,-.010759,
.009,-.010464,
.009571,-.010064,
.010064,-.009571,
.010464,-.009,
.010759,-.008368,
.010939,-.007695,
.011,-.007,
.011,.007,
.010939,.007695,
.010759,.008368,
.010464,.009,
.010064,.009571,
.009571,.010064,
.009,.010464,
.008368,.010759,
.007695,.010939,
.007,.011,
-.007,.011,
-.007695,.010939,
-.008368,.010759,
-.009,.010464,
-.009571,.010064,
-.010064,.009571,
-.010464,.009,
-.010759,.008368,
-.010939,.007695,
-.011,.007,
-.011,-.007,
-.010939,-.007695,
-.010759,-.008368,
-.010464,-.009,
-.010064,-.009571,
-.009571,-.010064,
-.009,-.010464,
-.008368,-.010759,
-.007695,-.010939,
-.007,-.011,
0.0*
%
%ADD13MACRO13*%
%AMMACRO24*
4,1,40,-.011,.007,
-.011,-.007,
-.010939,-.007695,
-.010759,-.008368,
-.010464,-.009,
-.010064,-.009571,
-.009571,-.010064,
-.009,-.010464,
-.008368,-.010759,
-.007695,-.010939,
-.007,-.011,
.007,-.011,
.007695,-.010939,
.008368,-.010759,
.009,-.010464,
.009571,-.010064,
.010064,-.009571,
.010464,-.009,
.010759,-.008368,
.010939,-.007695,
.011,-.007,
.011,.007,
.010939,.007695,
.010759,.008368,
.010464,.009,
.010064,.009571,
.009571,.010064,
.009,.010464,
.008368,.010759,
.007695,.010939,
.007,.011,
-.007,.011,
-.007695,.010939,
-.008368,.010759,
-.009,.010464,
-.009571,.010064,
-.010064,.009571,
-.010464,.009,
-.010759,.008368,
-.010939,.007695,
-.011,.007,
0.0*
%
%ADD24MACRO24*%
%ADD79C,.01*%
%ADD80C,.02*%
%ADD81C,.006*%
G75*
%LPD*%
G75*
G36*
G01X1017308Y1433722D02*
Y1451397D01*
X991708D01*
Y1433722D01*
X1017308D01*
G37*
G36*
G01Y1453247D02*
Y1470922D01*
X991708D01*
Y1453247D01*
X1017308D01*
G37*
G36*
G01Y1473722D02*
Y1491397D01*
X991708D01*
Y1473722D01*
X1017308D01*
G37*
G36*
G01Y1493247D02*
Y1510922D01*
X991708D01*
Y1493247D01*
X1017308D01*
G37*
G36*
G01Y1513722D02*
Y1531397D01*
X991708D01*
Y1513722D01*
X1017308D01*
G37*
G36*
G01Y1553722D02*
Y1571397D01*
X991708D01*
Y1553722D01*
X1017308D01*
G37*
G36*
G01Y1533247D02*
Y1550922D01*
X991708D01*
Y1533247D01*
X1017308D01*
G37*
G36*
G01Y1573247D02*
Y1590922D01*
X991708D01*
Y1573247D01*
X1017308D01*
G37*
G36*
G01X991708Y1593722D02*
X1017307D01*
Y1610922D01*
X991708D01*
Y1593722D01*
G37*
G54D10*
X-38666Y47522D03*
X-37468Y1947630D03*
X21499Y17050D03*
X1010999Y18550D03*
X1008999Y1968550D03*
X1073242Y50048D03*
G54D20*
X35500Y597400D03*
Y593300D03*
X34699Y616050D03*
X38800Y607326D03*
Y603200D03*
X22799Y1065050D03*
X21699Y1936050D03*
Y1944050D03*
X51799Y217100D03*
X43100Y597400D03*
X48400Y635500D03*
Y639600D03*
X60449Y656487D03*
Y652487D03*
Y648487D03*
X41699Y1838050D03*
Y1842050D03*
X79199Y642550D03*
X82700Y1013000D03*
X67299Y1851900D03*
X87299Y1000450D03*
Y1004450D03*
X101299Y1081700D03*
Y1077400D03*
X92700Y1553500D03*
Y1557500D03*
X122199Y1125050D03*
X123699Y1343050D03*
X123199Y1356050D03*
Y1352050D03*
X118949Y1476050D03*
X109199Y1716613D03*
Y1720613D03*
X137699Y423113D03*
Y427113D03*
X139600Y1210400D03*
X128000Y1319900D03*
X131700Y1365000D03*
X158199Y165050D03*
Y161050D03*
X157499Y540050D03*
Y544250D03*
X157699Y570050D03*
Y566050D03*
X158199Y975550D03*
Y971550D03*
X147699Y1722550D03*
Y1718550D03*
X158171Y1786909D03*
Y1782909D03*
X182826Y82428D03*
X180199Y156550D03*
Y165050D03*
Y161050D03*
X172400Y424400D03*
X180199Y572050D03*
Y568050D03*
Y564050D03*
X174700Y922700D03*
X183800Y931600D03*
X179949Y976550D03*
Y972550D03*
X180199Y967550D03*
X180764Y1786613D03*
Y1782613D03*
Y1778613D03*
X198800Y823000D03*
X194699Y1381050D03*
Y1377050D03*
Y1373050D03*
X198749Y1635113D03*
Y1630613D03*
X229700Y689500D03*
X227950Y1082500D03*
X228200Y1480100D03*
X233699Y101050D03*
Y97050D03*
X232100Y283000D03*
X233100Y1499300D03*
X305700Y90700D03*
X308699Y343550D03*
X310199Y360050D03*
Y356050D03*
Y750050D03*
X311199Y767050D03*
Y762550D03*
X310199Y1573050D03*
X306699Y1562550D03*
X310199Y1577050D03*
X313558Y1953328D03*
X313477Y1966191D03*
Y1962191D03*
X337699Y63050D03*
Y67050D03*
X378699Y53050D03*
Y57050D03*
X386699Y30550D03*
Y26050D03*
X404199Y51050D03*
Y56050D03*
X651749Y1803634D03*
Y1796134D03*
X651249Y1818634D03*
X697249Y1821634D03*
Y1825634D03*
X739749Y1806634D03*
Y1798634D03*
Y1814134D03*
X779100Y336200D03*
X777800Y736700D03*
X777900Y1138200D03*
X780500Y1543100D03*
X777749Y1817634D03*
X779699Y1949050D03*
X789249Y1804634D03*
Y1800634D03*
X817199Y1825550D03*
Y1821550D03*
X849178Y280924D03*
X847896Y681882D03*
X847533Y1087392D03*
X861799Y1372200D03*
X849527Y1492296D03*
X850014Y1898113D03*
X874928Y163924D03*
Y159924D03*
X886699Y570550D03*
Y565050D03*
X886533Y975892D03*
Y971892D03*
X873527Y1379796D03*
Y1375796D03*
X881801Y1720950D03*
X886300Y1786300D03*
X886264Y1782213D03*
X905699Y99050D03*
X889301Y1720950D03*
X925928Y168424D03*
Y164424D03*
X925699Y172550D03*
X908646Y570882D03*
Y566882D03*
Y562882D03*
X908533Y974392D03*
Y970392D03*
Y966392D03*
X908264Y1785613D03*
Y1781613D03*
Y1777613D03*
G54D11*
X-38436Y23633D03*
X-36811Y1104775D03*
X-35919Y1969497D03*
X1072493Y21507D03*
X1075940Y1769358D03*
G54D30*
X44368Y1946712D03*
G54D21*
X34699Y611550D03*
X21699Y1948050D03*
Y1952050D03*
Y1940050D03*
X59199Y203550D03*
Y207550D03*
Y211550D03*
X59699Y1017050D03*
X59636Y1021050D03*
Y1025050D03*
X55699Y1897050D03*
X81199Y204550D03*
Y208550D03*
X81201Y611450D03*
Y615450D03*
X77199Y1837550D03*
X77449Y1843113D03*
X77199Y1849050D03*
X84700Y1008500D03*
X100700Y1115400D03*
X103949Y1476050D03*
X85949Y1828613D03*
Y1832613D03*
X108950Y972000D03*
X108899Y967850D03*
X116199Y1298113D03*
X111449Y1476050D03*
X117449Y1702613D03*
X128180Y1098482D03*
Y1094482D03*
X142100Y1335800D03*
X131199Y1342050D03*
X131700Y1361000D03*
X151699Y517613D03*
X159399Y524850D03*
X166899D03*
X147200Y545000D03*
X182872Y90572D03*
Y86572D03*
X186599Y152000D03*
X174399Y524850D03*
X186599Y559300D03*
X174699Y916113D03*
X187099Y963100D03*
X174200Y1691200D03*
X186099Y1773200D03*
X202599Y1367400D03*
X229698Y287114D03*
X229699Y693550D03*
X233572Y92572D03*
X233699Y105050D03*
X241699Y95550D03*
X244000Y269700D03*
X243400Y677100D03*
X305699Y86613D03*
X308699Y334050D03*
Y339050D03*
X310199Y742050D03*
Y746050D03*
X306699Y1554550D03*
Y1558550D03*
X313921Y1944909D03*
Y1948909D03*
X319600Y105200D03*
X333198Y337114D03*
Y333114D03*
X318400Y365200D03*
X334699Y745050D03*
Y741050D03*
X319400Y772200D03*
X331199Y1553550D03*
Y1557550D03*
X318400Y1582600D03*
X321600Y1971900D03*
X339421Y1947409D03*
Y1943409D03*
X378800Y42300D03*
X700749Y1801634D03*
Y1808634D03*
X754678Y323924D03*
Y328924D03*
X753396Y724882D03*
Y729882D03*
X754033Y1126392D03*
Y1131392D03*
X757027Y1531296D03*
Y1536296D03*
X753514Y1937713D03*
Y1942213D03*
X779699Y326550D03*
Y322550D03*
X771678Y347924D03*
Y352424D03*
X777699Y724050D03*
Y728550D03*
X769896Y748382D03*
Y752882D03*
X778699Y1127550D03*
Y1123550D03*
X770033Y1152392D03*
Y1156892D03*
X780881Y1527893D03*
Y1531893D03*
X772527Y1554796D03*
Y1559296D03*
X778199Y1935050D03*
Y1939050D03*
X770014Y1960713D03*
Y1965213D03*
X800699Y336050D03*
Y332050D03*
X799199Y736050D03*
Y732050D03*
Y1133050D03*
Y1137050D03*
X801881Y1538893D03*
Y1542893D03*
X800381Y1944393D03*
Y1948393D03*
X816699Y167050D03*
X817199Y1788050D03*
X824199Y167050D03*
X831699D03*
X824699Y1788050D03*
X832199D03*
X849200Y276800D03*
X847900Y677700D03*
X847500Y1083200D03*
X849500Y1488100D03*
X849999Y1893850D03*
X873199Y1359550D03*
Y1363550D03*
Y1367550D03*
X905699Y107050D03*
Y103050D03*
X916099Y557800D03*
X916599Y962100D03*
X916099Y1771700D03*
X931099Y158500D03*
G54D12*
X12569Y372041D03*
Y375978D03*
Y379915D03*
Y383852D03*
Y387789D03*
Y391726D03*
Y395663D03*
Y399600D03*
Y403537D03*
Y407474D03*
Y411411D03*
Y431098D03*
Y427161D03*
Y423223D03*
Y435035D03*
Y438972D03*
Y442909D03*
Y446846D03*
Y450783D03*
Y454720D03*
Y458657D03*
Y462594D03*
Y466531D03*
Y470468D03*
Y474405D03*
Y478342D03*
Y482279D03*
Y486216D03*
Y490153D03*
Y494090D03*
Y498027D03*
Y501964D03*
Y505901D03*
Y509838D03*
Y513775D03*
Y517712D03*
Y521649D03*
Y525586D03*
Y529523D03*
Y533460D03*
Y537397D03*
Y541334D03*
Y545271D03*
Y549208D03*
Y553145D03*
Y557082D03*
Y561019D03*
Y564956D03*
Y568893D03*
Y572830D03*
Y576767D03*
Y580704D03*
Y584641D03*
Y588578D03*
Y592515D03*
Y596452D03*
Y600389D03*
Y604326D03*
Y608263D03*
Y612200D03*
Y616137D03*
Y620074D03*
Y624011D03*
Y627948D03*
Y631885D03*
Y635822D03*
Y639759D03*
Y643696D03*
Y647633D03*
Y651570D03*
Y655507D03*
Y659444D03*
Y663381D03*
Y671255D03*
Y667318D03*
Y675192D03*
Y679129D03*
Y683066D03*
Y687003D03*
Y690940D03*
Y694877D03*
Y698814D03*
X12560Y793325D03*
Y789388D03*
Y785451D03*
Y781514D03*
Y813010D03*
Y809073D03*
Y805136D03*
Y801199D03*
Y797262D03*
Y832696D03*
Y820884D03*
Y816947D03*
Y856318D03*
Y852381D03*
Y848444D03*
Y844507D03*
Y840570D03*
Y836633D03*
X12569Y1356293D03*
Y1360230D03*
Y1364167D03*
Y1368104D03*
Y1372041D03*
Y1375978D03*
Y1379915D03*
Y1383852D03*
Y1387789D03*
Y1391726D03*
Y1395663D03*
Y1415350D03*
Y1411413D03*
Y1407475D03*
Y1419287D03*
Y1423224D03*
Y1427161D03*
Y1431098D03*
Y1435035D03*
Y1438972D03*
Y1442909D03*
Y1446846D03*
Y1450783D03*
Y1454720D03*
Y1458657D03*
Y1462594D03*
Y1466531D03*
Y1470468D03*
Y1474405D03*
Y1478342D03*
Y1482279D03*
Y1486216D03*
Y1490153D03*
Y1494090D03*
Y1498027D03*
Y1501964D03*
Y1505901D03*
Y1509838D03*
Y1513775D03*
Y1517712D03*
Y1521649D03*
Y1525586D03*
Y1529523D03*
Y1533460D03*
Y1537397D03*
Y1541334D03*
Y1545271D03*
Y1549208D03*
Y1553145D03*
Y1557082D03*
Y1561019D03*
Y1564956D03*
Y1568893D03*
Y1572830D03*
Y1576767D03*
Y1580704D03*
Y1584641D03*
Y1588578D03*
Y1592515D03*
Y1596452D03*
Y1600389D03*
Y1604326D03*
Y1608263D03*
Y1612200D03*
Y1616137D03*
Y1620074D03*
Y1624011D03*
Y1627948D03*
Y1631885D03*
Y1635822D03*
Y1639759D03*
Y1643696D03*
Y1655507D03*
Y1651570D03*
Y1647633D03*
Y1659444D03*
Y1663381D03*
Y1667318D03*
Y1675192D03*
Y1671255D03*
Y1679129D03*
Y1683066D03*
X12560Y1765766D03*
Y1785451D03*
Y1781514D03*
Y1777577D03*
Y1773640D03*
Y1769703D03*
Y1805136D03*
Y1801199D03*
Y1797262D03*
Y1793325D03*
Y1789388D03*
Y1828759D03*
Y1824822D03*
Y1820885D03*
Y1816948D03*
Y1840570D03*
Y1836633D03*
Y1832696D03*
G54D13*
X19399Y1065050D03*
X18299Y1936050D03*
Y1944050D03*
X32100Y597400D03*
Y593300D03*
X39700Y597400D03*
X31299Y616050D03*
X35400Y607326D03*
Y603200D03*
X38299Y1838050D03*
Y1842050D03*
X48399Y217100D03*
X45000Y635500D03*
Y639600D03*
X57049Y656487D03*
Y652487D03*
Y648487D03*
X75799Y642550D03*
X79300Y1013000D03*
X63899Y1851900D03*
X83899Y1000450D03*
Y1004450D03*
X97899Y1081700D03*
Y1077400D03*
X89300Y1553500D03*
Y1557500D03*
X118799Y1125050D03*
X124600Y1319900D03*
X120299Y1343050D03*
X119799Y1356050D03*
Y1352050D03*
X115549Y1476050D03*
X105799Y1716613D03*
Y1720613D03*
X134299Y423113D03*
Y427113D03*
X136200Y1210400D03*
X128300Y1365000D03*
X144299Y1722550D03*
Y1718550D03*
X154799Y165050D03*
Y161050D03*
X154099Y540050D03*
Y544250D03*
X154299Y570050D03*
Y566050D03*
X154799Y975550D03*
Y971550D03*
X154771Y1786909D03*
Y1782909D03*
X179426Y82428D03*
X176799Y156550D03*
Y165050D03*
Y161050D03*
X169000Y424400D03*
X176799Y572050D03*
Y568050D03*
Y564050D03*
X171300Y922700D03*
X180400Y931600D03*
X176549Y976550D03*
Y972550D03*
X176799Y967550D03*
X177364Y1786613D03*
Y1782613D03*
Y1778613D03*
X195400Y823000D03*
X191299Y1381050D03*
Y1377050D03*
Y1373050D03*
X195349Y1635113D03*
Y1630613D03*
X230299Y101050D03*
Y97050D03*
X228700Y283000D03*
X226300Y689500D03*
X224550Y1082500D03*
X224800Y1480100D03*
X229700Y1499300D03*
X302300Y90700D03*
X305299Y343550D03*
X306799Y360050D03*
Y356050D03*
Y750050D03*
X307799Y767050D03*
Y762550D03*
X306799Y1573050D03*
X303299Y1562550D03*
X306799Y1577050D03*
X310158Y1953328D03*
X310077Y1966191D03*
Y1962191D03*
X334299Y63050D03*
Y67050D03*
X375299Y53050D03*
Y57050D03*
X383299Y30550D03*
Y26050D03*
X400799Y51050D03*
Y56050D03*
X648349Y1803634D03*
Y1796134D03*
X647849Y1818634D03*
X693849Y1821634D03*
Y1825634D03*
X736349Y1806634D03*
Y1798634D03*
Y1814134D03*
X775700Y336200D03*
X774400Y736700D03*
X774500Y1138200D03*
X777100Y1543100D03*
X774349Y1817634D03*
X776299Y1949050D03*
X785849Y1804634D03*
Y1800634D03*
X813799Y1825550D03*
Y1821550D03*
X844496Y681882D03*
X844133Y1087392D03*
X845778Y280924D03*
X858399Y1372200D03*
X846127Y1492296D03*
X846614Y1898113D03*
X871528Y163924D03*
Y159924D03*
X883299Y570550D03*
Y565050D03*
X883133Y975892D03*
Y971892D03*
X870127Y1379796D03*
Y1375796D03*
X878401Y1720950D03*
X885901D03*
X882900Y1786300D03*
X882864Y1782213D03*
X902299Y99050D03*
X905246Y570882D03*
Y566882D03*
Y562882D03*
X905133Y974392D03*
Y970392D03*
Y966392D03*
X904864Y1785613D03*
Y1781613D03*
Y1777613D03*
X922528Y168424D03*
Y164424D03*
X922299Y172550D03*
G54D40*
X77166Y114212D03*
Y117362D03*
Y120511D03*
Y123661D03*
Y126811D03*
Y129960D03*
Y133110D03*
Y519724D03*
Y522874D03*
Y526023D03*
Y529173D03*
Y532323D03*
Y535472D03*
Y538622D03*
Y925236D03*
Y928386D03*
Y931535D03*
Y934685D03*
Y937835D03*
Y940984D03*
Y944134D03*
Y1330748D03*
Y1333898D03*
Y1337047D03*
Y1340197D03*
Y1343347D03*
Y1346496D03*
Y1349646D03*
Y1736260D03*
Y1739410D03*
Y1742559D03*
Y1745709D03*
Y1748859D03*
Y1752008D03*
Y1755158D03*
X159055Y243267D03*
Y240118D03*
Y236968D03*
Y255866D03*
Y252716D03*
Y249567D03*
Y246417D03*
Y642480D03*
Y661378D03*
Y658228D03*
Y655079D03*
Y651929D03*
Y648779D03*
Y645630D03*
Y1066890D03*
Y1063740D03*
Y1060591D03*
Y1057441D03*
Y1054291D03*
Y1051142D03*
Y1047992D03*
Y1469252D03*
Y1466103D03*
Y1462953D03*
Y1459803D03*
Y1456654D03*
Y1453504D03*
Y1472402D03*
Y1871615D03*
Y1868465D03*
Y1865315D03*
Y1862166D03*
Y1859016D03*
Y1877914D03*
Y1874764D03*
X887401Y243267D03*
Y240118D03*
Y236968D03*
Y255866D03*
Y252716D03*
Y249567D03*
Y246417D03*
Y642480D03*
Y661378D03*
Y658228D03*
Y655079D03*
Y651929D03*
Y648779D03*
Y645630D03*
Y1066890D03*
Y1063740D03*
Y1060591D03*
Y1057441D03*
Y1054291D03*
Y1051142D03*
Y1047992D03*
Y1469252D03*
Y1466103D03*
Y1462953D03*
Y1459803D03*
Y1456654D03*
Y1453504D03*
Y1472402D03*
Y1871615D03*
Y1868465D03*
Y1865315D03*
Y1862166D03*
Y1859016D03*
Y1877914D03*
Y1874764D03*
G54D22*
X20849Y1059925D03*
Y1052175D03*
X28349Y1056050D03*
X42449Y211775D03*
Y204025D03*
X49949Y207900D03*
X60449Y1846475D03*
Y1838725D03*
X74049Y648025D03*
Y655775D03*
X66549Y651900D03*
X67949Y1842600D03*
X137249Y1347675D03*
Y1355425D03*
X129749Y1351550D03*
X186049Y161200D03*
Y568400D03*
Y972100D03*
X186549Y1782500D03*
X193549Y157325D03*
Y165075D03*
Y564525D03*
Y572275D03*
Y968225D03*
Y975975D03*
X208049Y1372925D03*
Y1380675D03*
X200549Y1376800D03*
X194049Y1778625D03*
Y1786375D03*
X856449Y1358925D03*
X863949Y1362800D03*
X856449Y1366675D03*
X922049Y563025D03*
Y570775D03*
X914549Y566900D03*
X922049Y967225D03*
Y974975D03*
X914549Y971100D03*
X921549Y1777125D03*
Y1784875D03*
X914049Y1781000D03*
X939549Y163825D03*
Y171575D03*
X932049Y167700D03*
G54D31*
X34525Y1956355D03*
X36494D03*
X38462D03*
Y1937069D03*
X36494D03*
X34525D03*
X40431Y1956355D03*
X42399D03*
X44368D03*
X46337D03*
X48305D03*
X50274D03*
X52242D03*
X54211D03*
Y1937069D03*
X52242D03*
X50274D03*
X48305D03*
X46337D03*
X44368D03*
X42399D03*
X40431D03*
G54D23*
X34599Y1588650D03*
X27030Y1925238D03*
X23030D03*
X19999Y1964850D03*
X31999Y1972350D03*
Y1964850D03*
X42700Y408900D03*
X49499Y1901850D03*
X83000Y1548300D03*
X79000D03*
X75000Y1565200D03*
X79000D03*
X97499Y1086850D03*
X101999D03*
X100700Y1107900D03*
X116499Y1223913D03*
Y1321413D03*
X120507Y1321496D03*
X116749Y1510150D03*
X112599D03*
X131999Y1224413D03*
X127499D03*
X162999Y443913D03*
X166999D03*
X150999Y440413D03*
X185999Y496450D03*
X181899D03*
X176499Y833413D03*
X185999Y842413D03*
X174499Y1649663D03*
X197499Y97850D03*
X205499D03*
X190499Y842413D03*
X205999Y898313D03*
X209999D03*
X226800Y1086600D03*
X225499Y1499350D03*
X231000Y1880500D03*
X247500Y1078550D03*
X236100Y1893900D03*
X280499Y341850D03*
X284999D03*
X281499Y748350D03*
X285499D03*
X278499Y1559350D03*
X282499D03*
X284358Y1951628D03*
X288358D03*
X399999Y39350D03*
X640049Y1803934D03*
Y1792934D03*
X649049Y1810934D03*
X655549Y1815434D03*
X712549Y1808634D03*
X706549Y1797934D03*
X744049Y1802934D03*
Y1795434D03*
Y1810434D03*
X833999Y204850D03*
X829499D03*
X827500Y267500D03*
X825700Y1075800D03*
X827700Y1480700D03*
X889700Y1704700D03*
X920499Y108350D03*
X912499D03*
X936499D03*
X948499D03*
G54D32*
X37999Y1968750D03*
Y1976350D03*
X53999Y778750D03*
Y786350D03*
X57068Y1966462D03*
Y1974062D03*
X83568Y1966462D03*
Y1974062D03*
X74568Y1966462D03*
Y1974062D03*
X65768Y1966462D03*
Y1974062D03*
X92568Y1966462D03*
Y1974062D03*
X240999Y89850D03*
Y82250D03*
G54D41*
X71773Y209631D03*
Y206431D03*
X66023Y209631D03*
Y206431D03*
X71773Y615143D03*
Y611943D03*
X66023Y615143D03*
Y611943D03*
X71773Y1020655D03*
Y1017455D03*
X66023Y1020655D03*
Y1017455D03*
X71773Y1426167D03*
Y1422967D03*
X66023Y1426167D03*
Y1422967D03*
X71773Y1828479D03*
X66023D03*
X71773Y1831679D03*
X66023D03*
X164448Y160447D03*
Y163647D03*
Y565959D03*
Y569159D03*
Y971471D03*
Y974671D03*
Y1376983D03*
Y1380183D03*
Y1782494D03*
Y1785694D03*
X170198Y160447D03*
Y163647D03*
Y565959D03*
Y569159D03*
Y971471D03*
Y974671D03*
Y1376983D03*
Y1380183D03*
Y1782494D03*
Y1785694D03*
X892794Y160447D03*
Y163647D03*
X898544Y160447D03*
Y163647D03*
X892794Y565959D03*
Y569159D03*
X898544Y565959D03*
Y569159D03*
X892794Y971471D03*
Y974671D03*
X898544Y971471D03*
Y974671D03*
X892794Y1376983D03*
Y1380183D03*
X898544Y1376983D03*
Y1380183D03*
X892794Y1782494D03*
Y1785694D03*
X898544Y1782494D03*
Y1785694D03*
G54D14*
X18499Y1923750D03*
X103999Y1235250D03*
X104499Y1267813D03*
X102100Y1638700D03*
X105499Y1673313D03*
X134300Y455000D03*
X139499Y488813D03*
X162999Y852813D03*
X162499Y886313D03*
X221498Y281314D03*
X221499Y687750D03*
X217500Y1084200D03*
X220999Y1497750D03*
X227814Y1891313D03*
X253200Y1534900D03*
X289099Y23313D03*
X293999Y56313D03*
X853978Y275124D03*
X852696Y676082D03*
X852333Y1081592D03*
X854327Y1486496D03*
X854814Y1892313D03*
X894800Y1704200D03*
G54D50*
X117999Y1143550D03*
Y1162050D03*
G54D24*
X34599Y1592050D03*
X27030Y1928638D03*
X23030D03*
X19999Y1968250D03*
X31999Y1975750D03*
Y1968250D03*
X42700Y412300D03*
X49499Y1905250D03*
X83000Y1551700D03*
X79000D03*
X75000Y1568600D03*
X79000D03*
X97499Y1090250D03*
X101999D03*
X100700Y1111300D03*
X116499Y1227313D03*
Y1324813D03*
X120507Y1324896D03*
X116749Y1513550D03*
X112599D03*
X131999Y1227813D03*
X127499D03*
X162999Y447313D03*
X166999D03*
X150999Y443813D03*
X185999Y499850D03*
X181899D03*
X185999Y845813D03*
X176499Y836813D03*
X174499Y1653063D03*
X197499Y101250D03*
X205499D03*
X190499Y845813D03*
X205999Y901713D03*
X209999D03*
X226800Y1090000D03*
X225499Y1502750D03*
X231000Y1883900D03*
X247500Y1081950D03*
X236100Y1897300D03*
X280499Y345250D03*
X284999D03*
X281499Y751750D03*
X285499D03*
X278499Y1562750D03*
X282499D03*
X284358Y1955028D03*
X288358D03*
X399999Y42750D03*
X640049Y1807334D03*
Y1796334D03*
X649049Y1814334D03*
X655549Y1818834D03*
X706549Y1801334D03*
X712549Y1812034D03*
X744049Y1806334D03*
Y1798834D03*
Y1813834D03*
X833999Y208250D03*
X829499D03*
X827500Y270900D03*
X825700Y1079200D03*
X827700Y1484100D03*
X889700Y1708100D03*
X920499Y111750D03*
X912499D03*
X936499D03*
X948499D03*
G54D42*
X67999Y774150D03*
Y798950D03*
X133521Y107677D03*
Y132477D03*
X154521Y107677D03*
Y132477D03*
X861999Y114650D03*
Y139450D03*
X882499Y114650D03*
Y139450D03*
G54D60*
X128099Y1598150D03*
X135699D03*
X232199Y33550D03*
Y42550D03*
Y51550D03*
Y69550D03*
Y60550D03*
X239799Y33550D03*
Y42550D03*
Y51550D03*
Y69550D03*
Y60550D03*
X951199Y46050D03*
Y55050D03*
Y64050D03*
Y73050D03*
Y82050D03*
X949199Y101550D03*
X958799Y46050D03*
Y55050D03*
Y64050D03*
Y73050D03*
Y82050D03*
X956799Y101550D03*
G54D15*
X18499Y1929350D03*
X103999Y1240850D03*
X104499Y1273413D03*
X102100Y1644300D03*
X105499Y1678913D03*
X134300Y460600D03*
X139499Y494413D03*
X162999Y858413D03*
X162499Y891913D03*
X221498Y286914D03*
X221499Y693350D03*
X217500Y1089800D03*
X220999Y1503350D03*
X227814Y1896913D03*
X253200Y1540500D03*
X289099Y28913D03*
X293999Y61913D03*
X853978Y280724D03*
X852696Y681682D03*
X852333Y1087192D03*
X854327Y1492096D03*
X854814Y1897913D03*
X894800Y1709800D03*
G54D33*
X62499Y733150D03*
Y759950D03*
X86499Y1147150D03*
Y1173950D03*
X104000Y1571600D03*
Y1598400D03*
X151499Y1634087D03*
Y1660887D03*
X262998Y333214D03*
Y360014D03*
X263999Y738650D03*
Y765450D03*
X262999Y1549650D03*
Y1576450D03*
Y1946150D03*
Y1972950D03*
X339499Y24650D03*
Y51450D03*
X815499Y326150D03*
Y352950D03*
X813499Y729150D03*
Y755950D03*
Y1131650D03*
Y1158450D03*
X816171Y1536904D03*
Y1563704D03*
X814999Y1940650D03*
Y1967450D03*
G54D51*
X105749Y1255113D03*
X124249D03*
X105749Y1288613D03*
X124249D03*
X106749Y1659613D03*
X125249D03*
X107249Y1693113D03*
X125749D03*
X140749Y474550D03*
X140999Y508113D03*
X159249Y474550D03*
X159499Y508113D03*
X164249Y873113D03*
Y906613D03*
X182749Y873113D03*
Y906613D03*
X219248Y296614D03*
Y329614D03*
X219749Y703050D03*
X219249Y737050D03*
X219250Y1103100D03*
X218050Y1513400D03*
X219249Y1546050D03*
X219684Y1906687D03*
X218184Y1942987D03*
X237748Y296614D03*
Y329614D03*
X238249Y703050D03*
X237749Y737050D03*
X237750Y1103100D03*
X236550Y1513400D03*
X237749Y1546050D03*
X238184Y1906687D03*
X236684Y1942987D03*
X295249Y43613D03*
Y77113D03*
X313749Y43613D03*
Y77113D03*
X837978Y290124D03*
X841478Y323924D03*
X836196Y691182D03*
X839249Y724550D03*
X836333Y1096692D03*
X839749Y1129550D03*
X838077Y1501596D03*
X842577Y1534296D03*
X838314Y1907313D03*
X841249Y1940550D03*
X856478Y290124D03*
X859978Y323924D03*
X854696Y691182D03*
X857749Y724550D03*
X854833Y1096692D03*
X858249Y1129550D03*
X856577Y1501596D03*
X861077Y1534296D03*
X856814Y1907313D03*
X859749Y1940550D03*
G54D52*
X120418Y1275613D03*
X121418Y1680113D03*
X131580Y1275613D03*
X132580Y1680113D03*
X155158Y495113D03*
X166320D03*
X178418Y893613D03*
X189580D03*
X233917Y309614D03*
X245079D03*
X234418Y716550D03*
X245580D03*
X233918Y1526050D03*
X245080D03*
X235843Y1920987D03*
X247005D03*
X309918Y64113D03*
X321080D03*
X842119Y303424D03*
X830957D03*
X840037Y704382D03*
X828875D03*
X840174Y1109892D03*
X829012D03*
X841708Y1514296D03*
X830546D03*
X841655Y1920613D03*
X830493D03*
G54D61*
X166499Y1277113D03*
X161499D03*
X156499D03*
Y1297113D03*
X161499D03*
X166499D03*
X167499Y1700113D03*
X162499D03*
X157499D03*
Y1720113D03*
X162499D03*
X167499D03*
X171499Y1277113D03*
Y1297113D03*
X172499Y1700113D03*
Y1720113D03*
X206499Y514113D03*
X201499D03*
X196499D03*
X191499D03*
Y534113D03*
X196499D03*
X201499D03*
X206499D03*
X229999Y912613D03*
X224999D03*
X219999D03*
X214999D03*
Y932613D03*
X219999D03*
X224999D03*
X229999D03*
X247299Y1136650D03*
X242299D03*
X237299D03*
X232299D03*
Y1156650D03*
X237299D03*
X242299D03*
X247299D03*
X355999Y86550D03*
X350999D03*
X345999D03*
Y106550D03*
X350999D03*
X355999D03*
X360999Y86550D03*
Y106550D03*
G54D43*
X84999Y1121050D03*
Y1126050D03*
Y1131050D03*
Y1136050D03*
X104999Y1131050D03*
Y1126050D03*
Y1121050D03*
Y1136050D03*
X138499Y1216113D03*
Y1221113D03*
Y1226113D03*
Y1231113D03*
X158499Y1216113D03*
Y1231113D03*
Y1226113D03*
Y1221113D03*
X168499Y1625613D03*
Y1630613D03*
Y1635613D03*
Y1640613D03*
X173999Y430050D03*
Y435050D03*
Y440050D03*
Y445050D03*
X188499Y1635613D03*
Y1630613D03*
Y1625613D03*
Y1640613D03*
X193999Y430050D03*
Y445050D03*
Y440050D03*
Y435050D03*
X198499Y828613D03*
Y833613D03*
Y838613D03*
Y843613D03*
X218499Y833613D03*
Y828613D03*
Y843613D03*
Y838613D03*
X253998Y295114D03*
Y300114D03*
Y305114D03*
Y310114D03*
X254499Y701550D03*
Y706550D03*
Y711550D03*
Y716550D03*
X252999Y1513050D03*
Y1518050D03*
Y1523050D03*
Y1528050D03*
X273998Y305114D03*
Y300114D03*
Y295114D03*
Y310114D03*
X274499Y706550D03*
Y701550D03*
Y716550D03*
Y711550D03*
X272999Y1528050D03*
Y1523050D03*
Y1518050D03*
Y1513050D03*
X255777Y1917191D03*
Y1922191D03*
Y1927191D03*
Y1932191D03*
X279999Y351050D03*
Y356050D03*
Y361050D03*
Y366050D03*
X280999Y757550D03*
Y762550D03*
Y767550D03*
Y772550D03*
X279999Y1568550D03*
Y1573550D03*
Y1578550D03*
Y1583550D03*
X275777Y1932191D03*
Y1927191D03*
Y1922191D03*
Y1917191D03*
X279777Y1961191D03*
Y1966191D03*
Y1971191D03*
Y1976191D03*
X299999Y366050D03*
Y361050D03*
Y356050D03*
Y351050D03*
X300999Y767550D03*
Y762550D03*
Y757550D03*
Y772550D03*
X299999Y1573550D03*
Y1568550D03*
Y1583550D03*
Y1578550D03*
X299777Y1976191D03*
Y1971191D03*
Y1966191D03*
Y1961191D03*
X356499Y21550D03*
Y26550D03*
Y31550D03*
Y36550D03*
X376499Y31550D03*
Y26550D03*
Y21550D03*
Y36550D03*
X777978Y341924D03*
Y346924D03*
Y351924D03*
Y356924D03*
X776696Y742382D03*
Y747382D03*
Y752382D03*
Y757382D03*
X776833Y1143892D03*
Y1148892D03*
Y1153892D03*
Y1158892D03*
X779327Y1548796D03*
Y1553796D03*
Y1558796D03*
Y1563796D03*
X776814Y1954713D03*
Y1959713D03*
Y1964713D03*
Y1969713D03*
X802873Y292471D03*
Y297471D03*
Y302471D03*
Y307471D03*
X797978Y346924D03*
Y341924D03*
Y356924D03*
Y351924D03*
X800831Y696853D03*
Y701853D03*
Y706853D03*
Y711853D03*
X796696Y747382D03*
Y742382D03*
Y757382D03*
Y752382D03*
X800841Y1101216D03*
Y1106216D03*
Y1111216D03*
Y1116216D03*
X796833Y1148892D03*
Y1143892D03*
Y1158892D03*
Y1153892D03*
X802245Y1503722D03*
Y1508722D03*
Y1513722D03*
Y1518722D03*
X799327Y1553796D03*
Y1548796D03*
Y1563796D03*
Y1558796D03*
X801436Y1910365D03*
Y1915365D03*
Y1920365D03*
Y1925365D03*
X796814Y1954713D03*
Y1969713D03*
Y1964713D03*
Y1959713D03*
X822873Y302471D03*
Y297471D03*
Y292471D03*
Y307471D03*
X820831Y706853D03*
Y701853D03*
Y696853D03*
Y711853D03*
X820841Y1106216D03*
Y1101216D03*
Y1116216D03*
Y1111216D03*
X822245Y1508722D03*
Y1503722D03*
Y1518722D03*
Y1513722D03*
X821436Y1910365D03*
Y1925365D03*
Y1920365D03*
Y1915365D03*
G54D34*
X63999Y1871050D03*
Y1882050D03*
X72999Y1871550D03*
Y1882550D03*
X102999Y1171550D03*
Y1182550D03*
X111999Y1171550D03*
X120999D03*
X111999Y1182550D03*
X120999D03*
X120499Y1233613D03*
X111499D03*
X120499Y1244613D03*
X111499D03*
Y1266613D03*
Y1277613D03*
X126199Y1638013D03*
X117500Y1638000D03*
X108799Y1638013D03*
X126199Y1649013D03*
X117500Y1649000D03*
X108799Y1649013D03*
X112499Y1671613D03*
Y1682613D03*
X140999Y453113D03*
Y464113D03*
X146499Y486613D03*
Y497613D03*
X129900Y1171500D03*
Y1182500D03*
X129499Y1233613D03*
X132700Y1254400D03*
X129499Y1244613D03*
X132700Y1265400D03*
X133999Y1659613D03*
Y1670613D03*
X158999Y453113D03*
X149999D03*
X167900Y453100D03*
X158999Y464113D03*
X149999D03*
X167900Y464100D03*
X169499Y885113D03*
Y896113D03*
X169999Y112550D03*
X178999D03*
X169999Y123550D03*
X178999D03*
X187999Y851613D03*
X178999D03*
X169999D03*
X187999Y862613D03*
X178999D03*
X169999D03*
X191499Y873113D03*
Y884113D03*
X225900Y307400D03*
Y318400D03*
X228998Y340614D03*
X220298D03*
X228998Y351614D03*
X220298D03*
X225499Y726050D03*
Y715050D03*
X229999Y749550D03*
X221299D03*
X229999Y760550D03*
X221299D03*
X224300Y1130200D03*
Y1119200D03*
X224999Y1524550D03*
Y1535550D03*
X229000Y1568100D03*
Y1557100D03*
X220300Y1568100D03*
Y1557100D03*
X225814Y1931113D03*
Y1920113D03*
X220300Y1953600D03*
X229000D03*
X220300Y1964600D03*
X229000D03*
X246498Y319114D03*
Y330114D03*
X237698Y340614D03*
Y351614D03*
X246499Y726050D03*
Y737050D03*
X238699Y749550D03*
Y760550D03*
X246499Y1535550D03*
Y1546550D03*
X237700Y1568100D03*
Y1557100D03*
X246314Y1934113D03*
Y1945113D03*
X237700Y1953600D03*
Y1964600D03*
X296099Y22113D03*
Y33113D03*
X314099Y22113D03*
Y33113D03*
X305099Y22113D03*
Y33113D03*
X300999Y55613D03*
Y66613D03*
X322499Y43613D03*
Y54613D03*
X832978Y313424D03*
Y324424D03*
X840800Y346800D03*
Y335800D03*
X830499Y715550D03*
Y726550D03*
X838796Y747582D03*
Y736582D03*
X830499Y1119550D03*
Y1130550D03*
X838833Y1152392D03*
Y1141392D03*
X833827Y1523796D03*
Y1534796D03*
X841500Y1556300D03*
Y1545300D03*
X832499Y1930050D03*
X840400Y1954000D03*
X832499Y1941050D03*
X840400Y1965000D03*
X846999Y135550D03*
Y124550D03*
X850999Y301550D03*
Y312550D03*
X849500Y346800D03*
Y335800D03*
X858200Y346800D03*
Y335800D03*
X848696Y702882D03*
Y713882D03*
X847496Y747582D03*
Y736582D03*
X856196Y747582D03*
Y736582D03*
X848413Y1107613D03*
Y1118613D03*
X847533Y1152392D03*
Y1141392D03*
X856233Y1152392D03*
Y1141392D03*
X850827Y1512296D03*
Y1523296D03*
X850200Y1556300D03*
Y1545300D03*
X858900Y1556300D03*
Y1545300D03*
X850314Y1929113D03*
Y1918113D03*
X849100Y1954000D03*
X857800D03*
X849100Y1965000D03*
X857800D03*
X896999Y136550D03*
Y125550D03*
G54D70*
X240849Y102050D03*
G54D16*
X18199Y1956050D03*
X36199Y1918050D03*
X101145Y525988D03*
Y522488D03*
X99745Y931489D03*
Y927989D03*
X100528Y1336952D03*
Y1333452D03*
X104028Y1361952D03*
Y1358452D03*
X101699Y1743050D03*
Y1739550D03*
X103699Y1764050D03*
Y1767550D03*
X105199Y129550D03*
Y126050D03*
Y145050D03*
Y141550D03*
X105145Y550988D03*
Y547488D03*
X104745Y956489D03*
Y952989D03*
X129150Y1081100D03*
Y1077600D03*
X179699Y99050D03*
X178399Y524850D03*
X697749Y1813134D03*
X835699Y167550D03*
X836199Y1788050D03*
X903699Y124550D03*
X951199Y96050D03*
G54D25*
X30499Y1592060D03*
X31999Y1922250D03*
X23999Y1968250D03*
X27999D03*
X46800Y412300D03*
X42900Y604800D03*
X103999Y1472000D03*
X119499Y1109750D03*
X109499Y1201813D03*
X105499D03*
X106999Y1227313D03*
X111999D03*
X111499Y1472000D03*
X115599Y1471950D03*
X141499Y443813D03*
X146499D03*
X136000Y532200D03*
X135999Y1706750D03*
X131999D03*
X159199Y520550D03*
X167199D03*
X166499Y812313D03*
X167499Y836813D03*
X152600Y1684600D03*
X174999Y74750D03*
X185499Y120750D03*
X174199Y520550D03*
X170499Y812313D03*
X172499Y836813D03*
X184600Y1376500D03*
X180500D03*
X201499Y101250D03*
X209499D03*
X192800Y1654500D03*
X217499Y101250D03*
X223436Y1897065D03*
X644049Y1807334D03*
Y1796334D03*
X710549Y1801334D03*
X708549Y1812034D03*
X754978Y339124D03*
X753196Y738582D03*
X755499Y1143750D03*
X756327Y1546496D03*
X753314Y1951913D03*
X816499Y162750D03*
X814999Y1783750D03*
X823999Y162750D03*
X831499D03*
X826100Y670100D03*
X833499Y1783750D03*
X824499D03*
X828000Y1884700D03*
X900499Y88250D03*
X903499Y131750D03*
X924499Y111750D03*
X916499D03*
X932499D03*
X944499D03*
X940499D03*
X952499D03*
G54D80*
G01X-87137Y-139897D02*
Y-107897D01*
G01X-75137Y-123897D02*
G02I-12000J0D01*
G01X-80287D02*
G02I-6850J0D01*
G01X-71137D02*
X-103137D01*
G01X-71137Y-139897D02*
Y-219897D01*
G01D02*
X1129963D01*
G01X-71137Y-175397D02*
X1129963D01*
G01X-71137Y-139897D02*
X1129963D01*
G01X342463D02*
Y-219897D01*
G01X479963Y-139897D02*
Y-219897D01*
G01X594963Y-139897D02*
Y-219897D01*
G01X762463Y-139897D02*
Y-219897D01*
G01X932463Y-139897D02*
Y-219897D01*
G01X1129963Y-139897D02*
Y-219897D01*
G01X1157963Y-123897D02*
G02I-12000J0D01*
G01X1152813D02*
G02I-6850J0D01*
G01X1161963D02*
X1129963D01*
G01X1145963Y-139897D02*
Y-107897D01*
G54D35*
X43999Y1964750D03*
X103499Y1297813D03*
X104999Y1702063D03*
X123999Y1734813D03*
X138999Y517313D03*
X142667Y1306460D03*
X132999Y1306813D03*
X137504Y1735523D03*
X161999Y915813D03*
X182499Y71250D03*
X194500Y499200D03*
X215900Y896900D03*
X292999Y86313D03*
X295500Y329200D03*
X298000Y735700D03*
X297000Y1549800D03*
X296858Y1944028D03*
X369300Y72300D03*
X389500Y72200D03*
X693549Y1813334D03*
X870201Y1709850D03*
X907999Y84750D03*
G54D62*
X180199Y95050D03*
X878601Y1693850D03*
X900699Y115050D03*
X890600Y1716200D03*
X965400Y1660500D03*
Y1665500D03*
G54D71*
X241500Y1085625D03*
X234000Y1089500D03*
Y1081750D03*
G54D44*
X76038Y1929550D03*
X110960D03*
G54D26*
X30499Y1588660D03*
X31999Y1918850D03*
X23999Y1964850D03*
X27999D03*
X46800Y408900D03*
X42900Y601400D03*
X103999Y1468600D03*
X119499Y1106350D03*
X109499Y1198413D03*
X105499D03*
X106999Y1223913D03*
X111999D03*
X111499Y1468600D03*
X115599Y1468550D03*
X141499Y440413D03*
X146499D03*
X136000Y528800D03*
X135999Y1703350D03*
X131999D03*
X159199Y517150D03*
X167199D03*
X166499Y808913D03*
X167499Y833413D03*
X152600Y1681200D03*
X174999Y71350D03*
X185499Y117350D03*
X174199Y517150D03*
X170499Y808913D03*
X172499Y833413D03*
X184600Y1373100D03*
X180500D03*
X201499Y97850D03*
X209499D03*
X192800Y1651100D03*
X217499Y97850D03*
X223436Y1893665D03*
X644049Y1803934D03*
Y1792934D03*
X708549Y1808634D03*
X710549Y1797934D03*
X754978Y335724D03*
X753196Y735182D03*
X755499Y1140350D03*
X756327Y1543096D03*
X753314Y1948513D03*
X816499Y159350D03*
X814999Y1780350D03*
X823999Y159350D03*
X831499D03*
X826100Y666700D03*
X833499Y1780350D03*
X824499D03*
X828000Y1881300D03*
X900499Y84850D03*
X903499Y128350D03*
X924499Y108350D03*
X916499D03*
X932499D03*
X944499D03*
X940499D03*
X952499D03*
G54D17*
X18299Y1948050D03*
Y1952050D03*
Y1940050D03*
X31299Y611550D03*
X55799Y203550D03*
Y207550D03*
Y211550D03*
X56299Y1017050D03*
X56236Y1021050D03*
Y1025050D03*
X52299Y1897050D03*
X77799Y204550D03*
Y208550D03*
X77801Y611450D03*
Y615450D03*
X81300Y1008500D03*
X82549Y1828613D03*
X73799Y1837550D03*
X74049Y1843113D03*
X82549Y1832613D03*
X73799Y1849050D03*
X97300Y1115400D03*
X100549Y1476050D03*
X105550Y972000D03*
X105499Y967850D03*
X124780Y1098482D03*
Y1094482D03*
X112799Y1298113D03*
X108049Y1476050D03*
X114049Y1702613D03*
X143800Y545000D03*
X138700Y1335800D03*
X127799Y1342050D03*
X128300Y1361000D03*
X148299Y517613D03*
X155999Y524850D03*
X163499D03*
X179472Y90572D03*
Y86572D03*
X183199Y152000D03*
X170999Y524850D03*
X183199Y559300D03*
X171299Y916113D03*
X183699Y963100D03*
X170800Y1691200D03*
X182699Y1773200D03*
X199199Y1367400D03*
X230172Y92572D03*
X230299Y105050D03*
X226298Y287114D03*
X226299Y693550D03*
X238299Y95550D03*
X240600Y269700D03*
X240000Y677100D03*
X302299Y86613D03*
X305299Y334050D03*
Y339050D03*
X315000Y365200D03*
X306799Y742050D03*
Y746050D03*
X303299Y1554550D03*
Y1558550D03*
X315000Y1582600D03*
X310521Y1944909D03*
Y1948909D03*
X316200Y105200D03*
X329798Y337114D03*
Y333114D03*
X331299Y745050D03*
Y741050D03*
X316000Y772200D03*
X327799Y1553550D03*
Y1557550D03*
X336021Y1947409D03*
Y1943409D03*
X318200Y1971900D03*
X375400Y42300D03*
X697349Y1801634D03*
Y1808634D03*
X751278Y323924D03*
Y328924D03*
X749996Y724882D03*
Y729882D03*
X750633Y1126392D03*
Y1131392D03*
X753627Y1531296D03*
Y1536296D03*
X750114Y1937713D03*
Y1942213D03*
X776299Y326550D03*
Y322550D03*
X768278Y347924D03*
Y352424D03*
X774299Y724050D03*
Y728550D03*
X766496Y748382D03*
Y752882D03*
X775299Y1127550D03*
Y1123550D03*
X766633Y1152392D03*
Y1156892D03*
X777481Y1527893D03*
Y1531893D03*
X769127Y1554796D03*
Y1559296D03*
X774799Y1935050D03*
Y1939050D03*
X766614Y1960713D03*
Y1965213D03*
X797299Y336050D03*
Y332050D03*
X795799Y736050D03*
Y732050D03*
Y1133050D03*
Y1137050D03*
X798481Y1538893D03*
Y1542893D03*
X796981Y1944393D03*
Y1948393D03*
X813299Y167050D03*
X820799D03*
X813799Y1788050D03*
X821299D03*
X828299Y167050D03*
X844500Y677700D03*
X844100Y1083200D03*
X828799Y1788050D03*
X845800Y276800D03*
X846100Y1488100D03*
X846599Y1893850D03*
X869799Y1359550D03*
Y1363550D03*
Y1367550D03*
X902299Y107050D03*
Y103050D03*
X927699Y158500D03*
X912699Y557800D03*
X913199Y962100D03*
X912699Y1771700D03*
G54D53*
X125725Y1326750D03*
X145000Y539050D03*
X141125Y531550D03*
X129600Y1334250D03*
X133475Y1326750D03*
X148875Y531550D03*
X157825Y1682050D03*
X165575D03*
X161700Y1689550D03*
X180025Y918250D03*
X187775D03*
X183900Y925750D03*
X307000Y105150D03*
X303125Y97650D03*
X310875D03*
G54D81*
G01X-53190Y-209897D02*
Y-192397D01*
G01X-44894D02*
X-53190Y-203189D01*
G01X-43584Y-209897D02*
X-49479Y-198231D01*
G01X-35909Y-209897D02*
Y-192397D01*
X-25865Y-209897D01*
Y-192397D01*
G01X-13387Y-209897D02*
X-15134Y-209605D01*
X-16662Y-208439D01*
X-17972Y-206689D01*
X-18846Y-204647D01*
X-19282Y-202314D01*
Y-199980D01*
X-18846Y-197647D01*
X-17972Y-195605D01*
X-16662Y-193856D01*
X-15134Y-192689D01*
X-13387Y-192397D01*
X-11641Y-192689D01*
X-10112Y-193856D01*
X-8802Y-195605D01*
X-7928Y-197647D01*
X-7492Y-199980D01*
Y-202314D01*
X-7928Y-204647D01*
X-8802Y-206689D01*
X-10112Y-208439D01*
X-11641Y-209605D01*
X-13387Y-209897D01*
G01X-472D02*
X8698Y-192397D01*
G01X-472D02*
X8698Y-209897D01*
G01X34310D02*
Y-192397D01*
X38676D01*
X40423Y-193272D01*
X41733Y-194439D01*
X42825Y-196188D01*
X43698Y-198231D01*
X43916Y-201147D01*
X43698Y-204064D01*
X42825Y-206106D01*
X41733Y-207856D01*
X40423Y-209022D01*
X38676Y-209897D01*
X34310D01*
G01X52246D02*
Y-192397D01*
X57705D01*
X59451Y-193272D01*
X60543Y-194439D01*
X60980Y-196772D01*
X60543Y-199106D01*
X59233Y-200564D01*
X57705Y-201439D01*
X52246D01*
G01X57705D02*
X60980Y-209897D01*
G01X71493Y-192397D02*
X76733D01*
G01X74113D02*
Y-209897D01*
G01X71493D02*
X76733D01*
G01X86154Y-192397D02*
X91613Y-209897D01*
X97072Y-192397D01*
G01X113480Y-209897D02*
X104746D01*
Y-192397D01*
X113480D01*
G01X109986Y-200855D02*
X104746D01*
G01X139746Y-209897D02*
Y-192397D01*
X144986D01*
X146733Y-193272D01*
X148043Y-195314D01*
X148480Y-197647D01*
X148043Y-199980D01*
X146951Y-201730D01*
X144986Y-202606D01*
X139746D01*
G01X157246Y-192397D02*
Y-209897D01*
X165980D01*
G01X173654D02*
X179113Y-192397D01*
X184572Y-209897D01*
G01X182606Y-203772D02*
X175619D01*
G01X191591Y-209897D02*
Y-192397D01*
X201635Y-209897D01*
Y-192397D01*
G01X218480Y-209897D02*
X209746D01*
Y-192397D01*
X218480D01*
G01X214986Y-200855D02*
X209746D01*
G01X250859Y-200564D02*
X251733Y-199689D01*
X252388Y-198231D01*
X252825Y-196188D01*
X252388Y-194439D01*
X251515Y-193272D01*
X249986Y-192397D01*
X244091D01*
Y-209897D01*
X251296D01*
X252825Y-208731D01*
X253698Y-206980D01*
X254135Y-204939D01*
X253698Y-202897D01*
X252388Y-201147D01*
X250859Y-200564D01*
X244091D01*
G01X266613Y-209897D02*
X264866Y-209605D01*
X263338Y-208439D01*
X262028Y-206689D01*
X261154Y-204647D01*
X260718Y-202314D01*
Y-199980D01*
X261154Y-197647D01*
X262028Y-195605D01*
X263338Y-193856D01*
X264866Y-192689D01*
X266613Y-192397D01*
X268359Y-192689D01*
X269888Y-193856D01*
X271198Y-195605D01*
X272072Y-197647D01*
X272508Y-199980D01*
Y-202314D01*
X272072Y-204647D01*
X271198Y-206689D01*
X269888Y-208439D01*
X268359Y-209605D01*
X266613Y-209897D01*
G01X278654D02*
X284113Y-192397D01*
X289572Y-209897D01*
G01X287606Y-203772D02*
X280619D01*
G01X297246Y-209897D02*
Y-192397D01*
X302705D01*
X304451Y-193272D01*
X305543Y-194439D01*
X305980Y-196772D01*
X305543Y-199106D01*
X304233Y-200564D01*
X302705Y-201439D01*
X297246D01*
G01X302705D02*
X305980Y-209897D01*
G01X314310D02*
Y-192397D01*
X318676D01*
X320423Y-193272D01*
X321733Y-194439D01*
X322825Y-196188D01*
X323698Y-198231D01*
X323916Y-201147D01*
X323698Y-204064D01*
X322825Y-206106D01*
X321733Y-207856D01*
X320423Y-209022D01*
X318676Y-209897D01*
X314310D01*
G01X94686Y-164897D02*
Y-147397D01*
X100363Y-161980D01*
X106040Y-147397D01*
Y-164897D01*
G01X117863D02*
X116553Y-164605D01*
X115243Y-163439D01*
X114369Y-161397D01*
X113933Y-159064D01*
X114369Y-156730D01*
X115243Y-154689D01*
X116553Y-153522D01*
X117863Y-153231D01*
X119173Y-153522D01*
X120483Y-154689D01*
X121356Y-156730D01*
X121575Y-159064D01*
X121356Y-161397D01*
X120483Y-163439D01*
X119173Y-164605D01*
X117863Y-164897D01*
G01X139293Y-147397D02*
Y-164897D01*
G01Y-162273D02*
X138420Y-163731D01*
X137109Y-164605D01*
X135581Y-164897D01*
X133835Y-164314D01*
X132525Y-162856D01*
X131651Y-161106D01*
X131433Y-159064D01*
X131651Y-157022D01*
X132525Y-155272D01*
X133835Y-153814D01*
X135581Y-153231D01*
X137109Y-153522D01*
X138201Y-154106D01*
X139293Y-155272D01*
G01X149588Y-157022D02*
X156575D01*
X155920Y-154980D01*
X154828Y-153814D01*
X153300Y-153231D01*
X151771Y-153522D01*
X150461Y-154397D01*
X149588Y-156439D01*
X149151Y-158189D01*
Y-159939D01*
X149588Y-161689D01*
X150680Y-163439D01*
X151990Y-164605D01*
X153518Y-164897D01*
X155046Y-164314D01*
X156575Y-162564D01*
G01X170363Y-164897D02*
Y-147397D01*
G01X376163Y-209897D02*
Y-192397D01*
X373543Y-195897D01*
G01Y-209897D02*
X378783D01*
G01X389515Y-195314D02*
X390825Y-193564D01*
X392353Y-192689D01*
X394100Y-192397D01*
X396283Y-192980D01*
X397811Y-194439D01*
X398248Y-196188D01*
X398030Y-197939D01*
X397156Y-199397D01*
X392790Y-202314D01*
X390825Y-204355D01*
X389515Y-207273D01*
X389078Y-209897D01*
X398248D01*
G01X413783D02*
Y-192397D01*
X405704Y-204939D01*
X416622D01*
G01X423860Y-206397D02*
X425169Y-208439D01*
X426916Y-209605D01*
X428881Y-209897D01*
X430628Y-209605D01*
X432375Y-208147D01*
X433466Y-206397D01*
X433685Y-204647D01*
X433248Y-202606D01*
X431720Y-201147D01*
X430191Y-200564D01*
X428226D01*
G01X430191D02*
X431501Y-199689D01*
X432593Y-198231D01*
X433030Y-196481D01*
X432593Y-194730D01*
X431501Y-193272D01*
X429536Y-192397D01*
X427571Y-192689D01*
X425606Y-193856D01*
G01X442015Y-195314D02*
X443325Y-193564D01*
X444853Y-192689D01*
X446600Y-192397D01*
X448783Y-192980D01*
X450311Y-194439D01*
X450748Y-196188D01*
X450530Y-197939D01*
X449656Y-199397D01*
X445290Y-202314D01*
X443325Y-204355D01*
X442015Y-207273D01*
X441578Y-209897D01*
X450748D01*
G01X363046Y-164897D02*
Y-147397D01*
X368286D01*
X370033Y-148272D01*
X371343Y-150314D01*
X371780Y-152647D01*
X371343Y-154980D01*
X370251Y-156730D01*
X368286Y-157606D01*
X363046D01*
G01X389716Y-148856D02*
X388406Y-147980D01*
X386878Y-147397D01*
X385131D01*
X383166Y-148272D01*
X381638Y-149730D01*
X380546Y-151481D01*
X379673Y-154397D01*
X379454Y-157022D01*
X379891Y-159647D01*
X380546Y-161397D01*
X381856Y-163147D01*
X383385Y-164314D01*
X384913Y-164897D01*
X386441D01*
X387970Y-164314D01*
X389280Y-163439D01*
X390372Y-162273D01*
G01X404159Y-155564D02*
X405033Y-154689D01*
X405688Y-153231D01*
X406125Y-151188D01*
X405688Y-149439D01*
X404815Y-148272D01*
X403286Y-147397D01*
X397391D01*
Y-164897D01*
X404596D01*
X406125Y-163731D01*
X406998Y-161980D01*
X407435Y-159939D01*
X406998Y-157897D01*
X405688Y-156147D01*
X404159Y-155564D01*
X397391D01*
G01X413363Y-170730D02*
X426463D01*
G01X432391Y-164897D02*
Y-147397D01*
X442435Y-164897D01*
Y-147397D01*
G01X454913Y-164897D02*
X453166Y-164605D01*
X451638Y-163439D01*
X450328Y-161689D01*
X449454Y-159647D01*
X449018Y-157314D01*
Y-154980D01*
X449454Y-152647D01*
X450328Y-150605D01*
X451638Y-148856D01*
X453166Y-147689D01*
X454913Y-147397D01*
X456659Y-147689D01*
X458188Y-148856D01*
X459498Y-150605D01*
X460372Y-152647D01*
X460808Y-154980D01*
Y-157314D01*
X460372Y-159647D01*
X459498Y-161689D01*
X458188Y-163439D01*
X456659Y-164605D01*
X454913Y-164897D01*
G01X505754Y-147397D02*
X511213Y-164897D01*
X516672Y-147397D01*
G01X533080Y-164897D02*
X524346D01*
Y-147397D01*
X533080D01*
G01X529586Y-155855D02*
X524346D01*
G01X541846Y-164897D02*
Y-147397D01*
X547305D01*
X549051Y-148272D01*
X550143Y-149439D01*
X550580Y-151772D01*
X550143Y-154106D01*
X548833Y-155564D01*
X547305Y-156439D01*
X541846D01*
G01X547305D02*
X550580Y-164897D01*
G01X563713Y-165480D02*
X563276Y-165189D01*
Y-164605D01*
X563713Y-164314D01*
X564150Y-164605D01*
Y-165189D01*
X563713Y-165480D01*
G01X537463Y-209897D02*
Y-192397D01*
X534843Y-195897D01*
G01Y-209897D02*
X540083D01*
G01X630546Y-147397D02*
Y-164897D01*
X639280D01*
G01X656343D02*
Y-153231D01*
G01Y-155272D02*
X655470Y-154106D01*
X654159Y-153522D01*
X652631Y-153231D01*
X651103Y-153814D01*
X649793Y-154980D01*
X648919Y-156730D01*
X648483Y-159064D01*
X648919Y-161397D01*
X649793Y-163147D01*
X651103Y-164314D01*
X652631Y-164897D01*
X654159Y-164605D01*
X655470Y-163731D01*
X656343Y-162564D01*
G01X665328Y-170147D02*
X666638Y-170730D01*
X668385Y-170147D01*
X669476Y-168981D01*
X670350Y-167522D01*
X671659Y-162856D01*
X674498Y-153231D01*
G01X667511D02*
X671659Y-162856D01*
G01X684138Y-157022D02*
X691125D01*
X690470Y-154980D01*
X689378Y-153814D01*
X687850Y-153231D01*
X686321Y-153522D01*
X685011Y-154397D01*
X684138Y-156439D01*
X683701Y-158189D01*
Y-159939D01*
X684138Y-161689D01*
X685230Y-163439D01*
X686540Y-164605D01*
X688068Y-164897D01*
X689596Y-164314D01*
X691125Y-162564D01*
G01X701856Y-164897D02*
Y-153231D01*
G01Y-155564D02*
X702948Y-154397D01*
X704040Y-153522D01*
X705568Y-153231D01*
X706659Y-153522D01*
X707970Y-154397D01*
G01X719138Y-162856D02*
X720230Y-164022D01*
X721758Y-164897D01*
X723068D01*
X724378Y-164314D01*
X725251Y-163439D01*
X725688Y-162273D01*
X725470Y-160522D01*
X724596Y-159647D01*
X720666Y-157897D01*
X719793Y-155855D01*
X720230Y-154397D01*
X721103Y-153522D01*
X722413Y-153231D01*
X723723Y-153522D01*
X725033Y-154397D01*
G01X652413Y-192397D02*
Y-209897D01*
G01X647391Y-192397D02*
X657435D01*
G01X665328Y-207564D02*
X667075Y-209022D01*
X669040Y-209897D01*
X670786D01*
X672533Y-209022D01*
X673843Y-207564D01*
X674498Y-205522D01*
X674061Y-203481D01*
X672970Y-201730D01*
X671005Y-200564D01*
X668385Y-199980D01*
X666856Y-198814D01*
X666201Y-196772D01*
X666638Y-194730D01*
X667730Y-193272D01*
X669258Y-192397D01*
X670786D01*
X672315Y-192980D01*
X673625Y-194439D01*
G01X681736Y-209897D02*
Y-192397D01*
X687413Y-206980D01*
X693090Y-192397D01*
Y-209897D01*
G01X700110D02*
Y-192397D01*
X704476D01*
X706223Y-193272D01*
X707533Y-194439D01*
X708625Y-196188D01*
X709498Y-198231D01*
X709716Y-201147D01*
X709498Y-204064D01*
X708625Y-206106D01*
X707533Y-207856D01*
X706223Y-209022D01*
X704476Y-209897D01*
X700110D01*
G01X781410Y-164897D02*
Y-147397D01*
X785776D01*
X787523Y-148272D01*
X788833Y-149439D01*
X789925Y-151188D01*
X790798Y-153231D01*
X791016Y-156147D01*
X790798Y-159064D01*
X789925Y-161106D01*
X788833Y-162856D01*
X787523Y-164022D01*
X785776Y-164897D01*
X781410D01*
G01X800438Y-157022D02*
X807425D01*
X806770Y-154980D01*
X805678Y-153814D01*
X804150Y-153231D01*
X802621Y-153522D01*
X801311Y-154397D01*
X800438Y-156439D01*
X800001Y-158189D01*
Y-159939D01*
X800438Y-161689D01*
X801530Y-163439D01*
X802840Y-164605D01*
X804368Y-164897D01*
X805896Y-164314D01*
X807425Y-162564D01*
G01X817938Y-162856D02*
X819030Y-164022D01*
X820558Y-164897D01*
X821868D01*
X823178Y-164314D01*
X824051Y-163439D01*
X824488Y-162273D01*
X824270Y-160522D01*
X823396Y-159647D01*
X819466Y-157897D01*
X818593Y-155855D01*
X819030Y-154397D01*
X819903Y-153522D01*
X821213Y-153231D01*
X822523Y-153522D01*
X823833Y-154397D01*
G01X838713Y-153231D02*
Y-164897D01*
G01Y-148564D02*
X838276Y-148272D01*
Y-147689D01*
X838713Y-147397D01*
X839150Y-147689D01*
Y-148272D01*
X838713Y-148564D01*
G01X853156Y-169272D02*
X854685Y-170439D01*
X856431Y-170730D01*
X857959Y-170439D01*
X859270Y-168981D01*
X860143Y-166939D01*
Y-153231D01*
G01Y-155564D02*
X859270Y-154397D01*
X857959Y-153522D01*
X856431Y-153231D01*
X854685Y-153814D01*
X853593Y-154980D01*
X852719Y-157022D01*
X852283Y-159064D01*
X852501Y-160814D01*
X853375Y-162856D01*
X854685Y-164314D01*
X856431Y-164897D01*
X857741Y-164605D01*
X859270Y-163439D01*
X860143Y-162273D01*
G01X870001Y-164897D02*
Y-153231D01*
G01Y-156147D02*
X870875Y-154689D01*
X872185Y-153522D01*
X873931Y-153231D01*
X875459Y-153522D01*
X876770Y-154689D01*
X877425Y-156730D01*
Y-164897D01*
G01X887938Y-157022D02*
X894925D01*
X894270Y-154980D01*
X893178Y-153814D01*
X891650Y-153231D01*
X890121Y-153522D01*
X888811Y-154397D01*
X887938Y-156439D01*
X887501Y-158189D01*
Y-159939D01*
X887938Y-161689D01*
X889030Y-163439D01*
X890340Y-164605D01*
X891868Y-164897D01*
X893396Y-164314D01*
X894925Y-162564D01*
G01X905656Y-164897D02*
Y-153231D01*
G01Y-155564D02*
X906748Y-154397D01*
X907840Y-153522D01*
X909368Y-153231D01*
X910459Y-153522D01*
X911770Y-154397D01*
G01X825596Y-209897D02*
Y-192397D01*
X831055D01*
X832801Y-193272D01*
X833893Y-194439D01*
X834330Y-196772D01*
X833893Y-199106D01*
X832583Y-200564D01*
X831055Y-201439D01*
X825596D01*
G01X831055D02*
X834330Y-209897D01*
G01X847463D02*
X846153Y-209605D01*
X844843Y-208439D01*
X843969Y-206397D01*
X843533Y-204064D01*
X843969Y-201730D01*
X844843Y-199689D01*
X846153Y-198522D01*
X847463Y-198231D01*
X848773Y-198522D01*
X850083Y-199689D01*
X850956Y-201730D01*
X851175Y-204064D01*
X850956Y-206397D01*
X850083Y-208439D01*
X848773Y-209605D01*
X847463Y-209897D01*
G01X861033D02*
Y-192397D01*
G01Y-201147D02*
X862125Y-199397D01*
X863435Y-198522D01*
X864745Y-198231D01*
X866709Y-198814D01*
X868020Y-199980D01*
X868893Y-202022D01*
Y-204355D01*
X868456Y-206689D01*
X867583Y-208439D01*
X866055Y-209605D01*
X864745Y-209897D01*
X863435Y-209605D01*
X862125Y-208731D01*
X861033Y-207273D01*
G01X952413Y-209897D02*
Y-192397D01*
X949793Y-195897D01*
G01Y-209897D02*
X955033D01*
G01X969913Y-192397D02*
X968166Y-192980D01*
X966856Y-194439D01*
X965983Y-196188D01*
X965328Y-198522D01*
X965110Y-201147D01*
X965328Y-203772D01*
X965983Y-206106D01*
X966856Y-207856D01*
X968166Y-209314D01*
X969913Y-209897D01*
X971659Y-209314D01*
X972970Y-207856D01*
X973843Y-206106D01*
X974498Y-203772D01*
X974716Y-201147D01*
X974498Y-198522D01*
X973843Y-196188D01*
X972970Y-194439D01*
X971659Y-192980D01*
X969913Y-192397D01*
G01X983483Y-210480D02*
X991343Y-192397D01*
G01X1004913Y-209897D02*
Y-192397D01*
X1002293Y-195897D01*
G01Y-209897D02*
X1007533D01*
G01X1018265Y-202606D02*
X1019793Y-200564D01*
X1021103Y-199397D01*
X1022850Y-198814D01*
X1024378Y-199397D01*
X1025470Y-200564D01*
X1026343Y-202314D01*
X1026561Y-204355D01*
X1026343Y-206106D01*
X1025470Y-207856D01*
X1024159Y-209314D01*
X1022631Y-209897D01*
X1020885Y-209314D01*
X1019356Y-207564D01*
X1018483Y-204939D01*
X1018265Y-202022D01*
X1018701Y-198231D01*
X1019356Y-196188D01*
X1020448Y-194147D01*
X1021976Y-192689D01*
X1023505Y-192397D01*
X1025033Y-192980D01*
X1026125Y-194439D01*
G01X1035983Y-210480D02*
X1043843Y-192397D01*
G01X1053265Y-195314D02*
X1054575Y-193564D01*
X1056103Y-192689D01*
X1057850Y-192397D01*
X1060033Y-192980D01*
X1061561Y-194439D01*
X1061998Y-196188D01*
X1061780Y-197939D01*
X1060906Y-199397D01*
X1056540Y-202314D01*
X1054575Y-204355D01*
X1053265Y-207273D01*
X1052828Y-209897D01*
X1061998D01*
G01X1074913Y-192397D02*
X1073166Y-192980D01*
X1071856Y-194439D01*
X1070983Y-196188D01*
X1070328Y-198522D01*
X1070110Y-201147D01*
X1070328Y-203772D01*
X1070983Y-206106D01*
X1071856Y-207856D01*
X1073166Y-209314D01*
X1074913Y-209897D01*
X1076659Y-209314D01*
X1077970Y-207856D01*
X1078843Y-206106D01*
X1079498Y-203772D01*
X1079716Y-201147D01*
X1079498Y-198522D01*
X1078843Y-196188D01*
X1077970Y-194439D01*
X1076659Y-192980D01*
X1074913Y-192397D01*
G01X1092413Y-209897D02*
Y-192397D01*
X1089793Y-195897D01*
G01Y-209897D02*
X1095033D01*
G01X1105765Y-195314D02*
X1107075Y-193564D01*
X1108603Y-192689D01*
X1110350Y-192397D01*
X1112533Y-192980D01*
X1114061Y-194439D01*
X1114498Y-196188D01*
X1114280Y-197939D01*
X1113406Y-199397D01*
X1109040Y-202314D01*
X1107075Y-204355D01*
X1105765Y-207273D01*
X1105328Y-209897D01*
X1114498D01*
G01X1000110Y-164897D02*
Y-147397D01*
X1004476D01*
X1006223Y-148272D01*
X1007533Y-149439D01*
X1008625Y-151188D01*
X1009498Y-153231D01*
X1009716Y-156147D01*
X1009498Y-159064D01*
X1008625Y-161106D01*
X1007533Y-162856D01*
X1006223Y-164022D01*
X1004476Y-164897D01*
X1000110D01*
G01X1026343D02*
Y-153231D01*
G01Y-155272D02*
X1025470Y-154106D01*
X1024159Y-153522D01*
X1022631Y-153231D01*
X1021103Y-153814D01*
X1019793Y-154980D01*
X1018919Y-156730D01*
X1018483Y-159064D01*
X1018919Y-161397D01*
X1019793Y-163147D01*
X1021103Y-164314D01*
X1022631Y-164897D01*
X1024159Y-164605D01*
X1025470Y-163731D01*
X1026343Y-162564D01*
G01X1039913Y-147397D02*
Y-164897D01*
G01X1036856Y-153231D02*
X1042970D01*
G01X1054138Y-157022D02*
X1061125D01*
X1060470Y-154980D01*
X1059378Y-153814D01*
X1057850Y-153231D01*
X1056321Y-153522D01*
X1055011Y-154397D01*
X1054138Y-156439D01*
X1053701Y-158189D01*
Y-159939D01*
X1054138Y-161689D01*
X1055230Y-163439D01*
X1056540Y-164605D01*
X1058068Y-164897D01*
X1059596Y-164314D01*
X1061125Y-162564D01*
G54D36*
X43999Y1968350D03*
X103499Y1301413D03*
X104999Y1705663D03*
X123999Y1738413D03*
X138999Y520913D03*
X142667Y1310060D03*
X132999Y1310413D03*
X137504Y1739123D03*
X161999Y919413D03*
X182499Y74850D03*
X194500Y502800D03*
X215900Y900500D03*
X292999Y89913D03*
X295500Y332800D03*
X298000Y739300D03*
X297000Y1553400D03*
X296858Y1947628D03*
X369300Y75900D03*
X389500Y75800D03*
X693549Y1816934D03*
X870201Y1713450D03*
X907999Y88350D03*
G54D45*
X91099Y1870050D03*
Y1890550D03*
X124500Y1583500D03*
X115899Y1870050D03*
Y1890550D03*
X149300Y1583500D03*
G54D72*
X242299Y1117109D03*
Y1128271D03*
G54D18*
X20799Y1973600D03*
X946999Y116200D03*
G54D54*
X122799Y1485350D03*
X159500Y821800D03*
X178999Y74850D03*
X213499Y101350D03*
X216998Y287414D03*
X216999Y693850D03*
X222900Y1090100D03*
X216999Y1503850D03*
X235499Y84850D03*
X232314Y1897413D03*
X312800Y321100D03*
X308999Y728350D03*
X309299Y1536750D03*
X313499Y1931850D03*
X655549Y1796434D03*
Y1803934D03*
X693549Y1801934D03*
Y1809434D03*
X755500Y709800D03*
X759500Y1922800D03*
X764500Y308300D03*
X779978Y308224D03*
X777500Y709800D03*
X760500Y1110800D03*
X778500D03*
X762000Y1516800D03*
X783200Y1516500D03*
X784500Y1922800D03*
X858478Y281224D03*
X857196Y682182D03*
X856833Y1087692D03*
X858827Y1492596D03*
X859314Y1898413D03*
X904499Y88350D03*
X928499Y111850D03*
G54D27*
X39799Y1918050D03*
X21799Y1956050D03*
X103345Y931489D03*
Y927989D03*
X104128Y1336952D03*
Y1333452D03*
X108799Y129550D03*
Y126050D03*
Y145050D03*
Y141550D03*
X104745Y525988D03*
Y522488D03*
X108745Y550988D03*
Y547488D03*
X108345Y956489D03*
Y952989D03*
X107628Y1361952D03*
Y1358452D03*
X105299Y1743050D03*
Y1739550D03*
X107299Y1764050D03*
Y1767550D03*
X132750Y1081100D03*
Y1077600D03*
X183299Y99050D03*
X181999Y524850D03*
X701349Y1813134D03*
X839299Y167550D03*
X839799Y1788050D03*
X907299Y124550D03*
X954799Y96050D03*
G54D63*
X185799Y95050D03*
X884201Y1693850D03*
X906299Y115050D03*
X896200Y1716200D03*
X971000Y1660500D03*
Y1665500D03*
G54D28*
X39799Y1921550D03*
X57299Y1901550D03*
X88300Y1097500D03*
Y1111500D03*
X109250Y1348100D03*
Y1344600D03*
X131799Y224550D03*
Y228050D03*
Y249050D03*
Y252550D03*
X127300Y433600D03*
X135238Y630065D03*
Y633565D03*
Y654565D03*
Y658065D03*
X132799Y1035550D03*
Y1039050D03*
Y1060050D03*
Y1063550D03*
X131190Y1441241D03*
Y1444741D03*
Y1465741D03*
Y1469241D03*
X131892Y1846254D03*
Y1849754D03*
Y1870754D03*
Y1874254D03*
X859278Y224924D03*
Y228424D03*
Y249424D03*
Y252924D03*
X859496Y630382D03*
Y633882D03*
Y654882D03*
Y658382D03*
X859133Y1035892D03*
Y1039392D03*
Y1060892D03*
Y1064392D03*
X860627Y1440796D03*
Y1444296D03*
Y1465796D03*
Y1469296D03*
X862614Y1846613D03*
Y1850113D03*
Y1871113D03*
Y1874613D03*
G54D37*
X49999Y1971850D03*
X107999Y1303913D03*
X109499Y1708413D03*
X143499Y523413D03*
X136600Y1180200D03*
X166499Y921913D03*
X218998Y317914D03*
X213598Y350914D03*
X218499Y724850D03*
X214599Y757850D03*
X217600Y1127800D03*
X217999Y1534850D03*
X218814Y1925913D03*
X213600Y1962400D03*
X297499Y92413D03*
X783049Y1819434D03*
X788049D03*
X858999Y311850D03*
X864900Y344900D03*
X855696Y712182D03*
X862896Y746382D03*
X855333Y1117692D03*
X862933Y1149192D03*
X857827Y1522596D03*
X865700Y1552400D03*
X857314Y1928413D03*
X864500Y1962200D03*
G54D46*
X105749Y1964050D03*
X121249D03*
X206249Y39550D03*
X221749D03*
X915749Y44550D03*
X931249D03*
G54D73*
X666399Y1806699D03*
Y1808664D03*
Y1810634D03*
Y1812604D03*
Y1814569D03*
X682699Y1806699D03*
Y1814569D03*
Y1812604D03*
Y1810634D03*
Y1808664D03*
G54D64*
X210676Y72528D03*
X928499Y85550D03*
G54D55*
X122799Y1481750D03*
X159500Y818200D03*
X178999Y71250D03*
X213499Y97750D03*
X216998Y283814D03*
X216999Y690250D03*
X222900Y1086500D03*
X216999Y1500250D03*
X235499Y81250D03*
X232314Y1893813D03*
X312800Y317500D03*
X308999Y724750D03*
X309299Y1533150D03*
X313499Y1928250D03*
X655549Y1792834D03*
Y1800334D03*
X693549Y1798334D03*
Y1805834D03*
X755500Y706200D03*
X759500Y1919200D03*
X764500Y304700D03*
X779978Y304624D03*
X777500Y706200D03*
X760500Y1107200D03*
X778500D03*
X762000Y1513200D03*
X783200Y1512900D03*
X784500Y1919200D03*
X858478Y277624D03*
X857196Y678582D03*
X856833Y1084092D03*
X858827Y1488996D03*
X859314Y1894813D03*
X904499Y84750D03*
X928499Y108250D03*
G54D19*
X20799Y1976300D03*
X946999Y118900D03*
G54D29*
X36199Y1921550D03*
X53699Y1901550D03*
X84700Y1097500D03*
Y1111500D03*
X123700Y433600D03*
X105650Y1348100D03*
Y1344600D03*
X128199Y224550D03*
Y228050D03*
Y249050D03*
Y252550D03*
X131638Y630065D03*
Y633565D03*
Y654565D03*
Y658065D03*
X129199Y1035550D03*
Y1039050D03*
Y1060050D03*
Y1063550D03*
X127590Y1441241D03*
Y1444741D03*
Y1465741D03*
Y1469241D03*
X128292Y1846254D03*
Y1849754D03*
Y1870754D03*
Y1874254D03*
X855678Y224924D03*
Y228424D03*
Y249424D03*
Y252924D03*
X855896Y630382D03*
Y633882D03*
Y654882D03*
Y658382D03*
X855533Y1035892D03*
Y1039392D03*
Y1060892D03*
Y1064392D03*
X857027Y1440796D03*
Y1444296D03*
Y1465796D03*
Y1469296D03*
X859014Y1846613D03*
Y1850113D03*
Y1871113D03*
Y1874613D03*
G54D47*
X109439Y1079300D03*
X111999D03*
X114559D03*
Y1085800D03*
X109439D03*
X106939Y1210363D03*
X109499D03*
X112059D03*
Y1216863D03*
X106939D03*
X120059Y1311800D03*
X117499D03*
X114939D03*
Y1305300D03*
X120059D03*
X145439Y426863D03*
Y433363D03*
X132939Y1714800D03*
X135499D03*
X138059D03*
Y1721300D03*
X132939D03*
X147999Y426863D03*
X150559D03*
Y433363D03*
X167439Y820363D03*
Y826863D03*
X169999Y820363D03*
X172559D03*
Y826863D03*
X208559Y891800D03*
X205999D03*
X203439D03*
Y885300D03*
X208559D03*
X278939Y327300D03*
X284059D03*
Y333800D03*
X281499D03*
X278939D03*
X285059Y740300D03*
X282499D03*
X279939D03*
Y733800D03*
X285059D03*
X284059Y1551300D03*
X281499D03*
X278939D03*
Y1544800D03*
X284059D03*
X283589Y1936200D03*
X288709D03*
Y1942700D03*
X286149D03*
X283589D03*
X790559Y327800D03*
X787999D03*
X785439D03*
Y321300D03*
X790559D03*
X790059Y728800D03*
X787499D03*
X784939D03*
Y722300D03*
X790059D03*
X789559Y1131800D03*
X786999D03*
X784439D03*
Y1125300D03*
X789559D03*
X787693Y1529128D03*
X792813D03*
Y1535628D03*
X790253D03*
X787693D03*
X785939Y1935800D03*
X791059D03*
Y1942300D03*
X788499D03*
X785939D03*
G54D56*
X116045Y1484981D03*
X113485D03*
X110925D03*
X108365D03*
Y1501161D03*
X110925D03*
X113485D03*
X116045D03*
X166437Y533288D03*
X163877D03*
Y549468D03*
X166437D03*
X171557Y533288D03*
X168997D03*
Y549468D03*
X171557D03*
X833013Y176949D03*
X830453D03*
X827893D03*
X825333D03*
Y193129D03*
X827893D03*
X830453D03*
X833013D03*
Y1798997D03*
X830453D03*
X827893D03*
X825333D03*
Y1815177D03*
X827893D03*
X830453D03*
X833013D03*
G54D65*
X201033Y62685D03*
Y64654D03*
Y66622D03*
Y68591D03*
Y70559D03*
Y72528D03*
Y74497D03*
Y76465D03*
Y78434D03*
Y80402D03*
Y82371D03*
X220319Y72528D03*
Y70559D03*
Y68591D03*
Y66622D03*
Y64654D03*
Y62685D03*
Y82371D03*
Y80402D03*
Y78434D03*
Y76465D03*
Y74497D03*
X918856Y75707D03*
Y77676D03*
Y79644D03*
Y81613D03*
Y83581D03*
Y85550D03*
Y87519D03*
Y89487D03*
Y91456D03*
Y93424D03*
Y95393D03*
X938142Y93424D03*
Y91456D03*
Y89487D03*
Y87519D03*
Y85550D03*
Y83581D03*
Y81613D03*
Y79644D03*
Y77676D03*
Y75707D03*
Y95393D03*
G54D74*
X753949Y1801294D03*
Y1803854D03*
Y1806414D03*
Y1808974D03*
X776149Y1806414D03*
Y1803854D03*
Y1801294D03*
Y1808974D03*
G54D38*
X49999Y1966250D03*
X107999Y1298313D03*
X109499Y1702813D03*
X143499Y517813D03*
X136600Y1174600D03*
X166499Y916313D03*
X218998Y312314D03*
X213598Y345314D03*
X218499Y719250D03*
X214599Y752250D03*
X217600Y1122200D03*
X217999Y1529250D03*
X218814Y1920313D03*
X213600Y1956800D03*
X297499Y86813D03*
X783049Y1813834D03*
X788049D03*
X858999Y306250D03*
X864900Y339300D03*
X855696Y706582D03*
X862896Y740782D03*
X855333Y1112092D03*
X862933Y1143592D03*
X857827Y1516996D03*
X865700Y1546800D03*
X857314Y1922813D03*
X864500Y1956600D03*
G54D66*
X231500Y269350D03*
X227625Y276850D03*
X230900Y676250D03*
X227025Y683750D03*
X228825Y1493450D03*
X235375Y276850D03*
X234775Y683750D03*
X232700Y1485950D03*
X236575Y1493450D03*
X240100Y1880450D03*
X243975Y1887950D03*
X236225D03*
X836700Y267450D03*
X840575Y274950D03*
X832825D03*
X835300Y670150D03*
X839175Y677650D03*
X831425D03*
X835000Y1075750D03*
X838875Y1083250D03*
X831125D03*
X836900Y1479050D03*
X840775Y1486550D03*
X833025D03*
X837499Y1884800D03*
X841374Y1892300D03*
X833624D03*
G54D39*
X85630Y41141D03*
Y46141D03*
Y51141D03*
Y56141D03*
Y61141D03*
Y66141D03*
Y71141D03*
Y76141D03*
Y81141D03*
Y86141D03*
Y91141D03*
Y96141D03*
Y101141D03*
Y106141D03*
Y111141D03*
Y136141D03*
Y141141D03*
Y146141D03*
Y151141D03*
Y156141D03*
Y161141D03*
Y166141D03*
Y446653D03*
Y451653D03*
Y456653D03*
Y461653D03*
Y466653D03*
Y471653D03*
Y476653D03*
Y481653D03*
Y486653D03*
Y491653D03*
Y496653D03*
Y501653D03*
Y506653D03*
Y511653D03*
Y516653D03*
Y541653D03*
Y546653D03*
Y551653D03*
Y556653D03*
Y561653D03*
Y566653D03*
Y571653D03*
Y852165D03*
Y857165D03*
Y862165D03*
Y867165D03*
Y872165D03*
Y877165D03*
Y882165D03*
Y887165D03*
Y892165D03*
Y897165D03*
Y902165D03*
Y907165D03*
Y912165D03*
Y917165D03*
Y922165D03*
Y947165D03*
Y952165D03*
Y957165D03*
Y962165D03*
Y967165D03*
Y972165D03*
Y977165D03*
Y1257677D03*
Y1262677D03*
Y1267677D03*
Y1272677D03*
Y1277677D03*
Y1282677D03*
Y1287677D03*
Y1292677D03*
Y1297677D03*
Y1302677D03*
Y1307677D03*
Y1312677D03*
Y1317677D03*
Y1322677D03*
Y1327677D03*
Y1352677D03*
Y1357677D03*
Y1362677D03*
Y1367677D03*
Y1372677D03*
Y1377677D03*
Y1382677D03*
Y1663189D03*
Y1668189D03*
Y1673189D03*
Y1678189D03*
Y1683189D03*
Y1688189D03*
Y1693189D03*
Y1698189D03*
Y1703189D03*
Y1708189D03*
Y1713189D03*
Y1718189D03*
Y1723189D03*
Y1728189D03*
Y1733189D03*
Y1758189D03*
Y1763189D03*
Y1768189D03*
Y1773189D03*
Y1778189D03*
Y1783189D03*
Y1788189D03*
X150591Y218937D03*
Y213937D03*
Y208937D03*
Y203937D03*
Y233937D03*
Y228937D03*
Y223937D03*
Y263937D03*
Y258937D03*
Y283937D03*
Y278937D03*
Y273937D03*
Y268937D03*
Y303937D03*
Y298937D03*
Y293937D03*
Y288937D03*
Y323937D03*
Y318937D03*
Y313937D03*
Y308937D03*
Y328937D03*
Y624449D03*
Y619449D03*
Y614449D03*
Y609449D03*
Y639449D03*
Y634449D03*
Y629449D03*
Y664449D03*
Y684449D03*
Y679449D03*
Y674449D03*
Y669449D03*
Y704449D03*
Y699449D03*
Y694449D03*
Y689449D03*
Y729449D03*
Y724449D03*
Y719449D03*
Y714449D03*
Y709449D03*
Y734449D03*
Y1024961D03*
Y1019961D03*
Y1014961D03*
Y1044961D03*
Y1039961D03*
Y1034961D03*
Y1029961D03*
Y1084961D03*
Y1079961D03*
Y1074961D03*
Y1069961D03*
Y1109961D03*
Y1104961D03*
Y1099961D03*
Y1094961D03*
Y1089961D03*
Y1129961D03*
Y1124961D03*
Y1119961D03*
Y1114961D03*
Y1139961D03*
Y1134961D03*
Y1425473D03*
Y1420473D03*
Y1445473D03*
Y1440473D03*
Y1435473D03*
Y1430473D03*
Y1450473D03*
Y1490473D03*
Y1485473D03*
Y1480473D03*
Y1475473D03*
Y1510473D03*
Y1505473D03*
Y1500473D03*
Y1495473D03*
Y1530473D03*
Y1525473D03*
Y1520473D03*
Y1515473D03*
Y1545473D03*
Y1540473D03*
Y1535473D03*
Y1825985D03*
Y1850985D03*
Y1845985D03*
Y1840985D03*
Y1835985D03*
Y1830985D03*
Y1855985D03*
Y1890985D03*
Y1885985D03*
Y1880985D03*
Y1910985D03*
Y1905985D03*
Y1900985D03*
Y1895985D03*
Y1930985D03*
Y1925985D03*
Y1920985D03*
Y1915985D03*
Y1950985D03*
Y1945985D03*
Y1940985D03*
Y1935985D03*
X878937Y218937D03*
Y213937D03*
Y208937D03*
Y203937D03*
Y233937D03*
Y228937D03*
Y223937D03*
Y263937D03*
Y258937D03*
Y283937D03*
Y278937D03*
Y273937D03*
Y268937D03*
Y303937D03*
Y298937D03*
Y293937D03*
Y288937D03*
Y323937D03*
Y318937D03*
Y313937D03*
Y308937D03*
Y328937D03*
Y624449D03*
Y619449D03*
Y614449D03*
Y609449D03*
Y639449D03*
Y634449D03*
Y629449D03*
Y664449D03*
Y684449D03*
Y679449D03*
Y674449D03*
Y669449D03*
Y704449D03*
Y699449D03*
Y694449D03*
Y689449D03*
Y729449D03*
Y724449D03*
Y719449D03*
Y714449D03*
Y709449D03*
Y734449D03*
Y1024961D03*
Y1019961D03*
Y1014961D03*
Y1044961D03*
Y1039961D03*
Y1034961D03*
Y1029961D03*
Y1084961D03*
Y1079961D03*
Y1074961D03*
Y1069961D03*
Y1109961D03*
Y1104961D03*
Y1099961D03*
Y1094961D03*
Y1089961D03*
Y1129961D03*
Y1124961D03*
Y1119961D03*
Y1114961D03*
Y1139961D03*
Y1134961D03*
Y1425473D03*
Y1420473D03*
Y1445473D03*
Y1440473D03*
Y1435473D03*
Y1430473D03*
Y1450473D03*
Y1490473D03*
Y1485473D03*
Y1480473D03*
Y1475473D03*
Y1510473D03*
Y1505473D03*
Y1500473D03*
Y1495473D03*
Y1530473D03*
Y1525473D03*
Y1520473D03*
Y1515473D03*
Y1545473D03*
Y1540473D03*
Y1535473D03*
Y1825985D03*
Y1850985D03*
Y1845985D03*
Y1840985D03*
Y1835985D03*
Y1830985D03*
Y1855985D03*
Y1890985D03*
Y1885985D03*
Y1880985D03*
Y1910985D03*
Y1905985D03*
Y1900985D03*
Y1895985D03*
Y1930985D03*
Y1925985D03*
Y1920985D03*
Y1915985D03*
Y1950985D03*
Y1945985D03*
Y1940985D03*
Y1935985D03*
G54D75*
X825300Y1726200D03*
X836300D03*
X888200Y1727300D03*
X877200D03*
X940400Y1486900D03*
X951400D03*
X940500Y1477500D03*
X951500D03*
G54D57*
X143999Y54089D03*
Y89011D03*
X862999Y60089D03*
Y95011D03*
G54D48*
X113499Y1106640D03*
Y1109200D03*
X106099D03*
Y1106640D03*
X113499Y1111760D03*
X106099D03*
X123299Y1216113D03*
Y1213553D03*
Y1218673D03*
X130699Y1213553D03*
Y1216113D03*
Y1218673D03*
X147400Y1324540D03*
Y1327100D03*
Y1329660D03*
X140000D03*
Y1327100D03*
Y1324540D03*
X158299Y433053D03*
X165699D03*
X158299Y438173D03*
Y435613D03*
X165699D03*
Y438173D03*
X181799Y834113D03*
Y831553D03*
X189199D03*
Y834113D03*
X181799Y836673D03*
X189199D03*
X179999Y1652987D03*
Y1650427D03*
Y1647867D03*
X187399D03*
Y1650427D03*
Y1652987D03*
X218100Y1882960D03*
Y1880400D03*
Y1877840D03*
X225500D03*
Y1880400D03*
Y1882960D03*
X242000Y1069000D03*
Y1071560D03*
Y1074120D03*
X234600D03*
Y1071560D03*
Y1069000D03*
X233600Y1478360D03*
Y1475800D03*
Y1473240D03*
X241000D03*
Y1475800D03*
Y1478360D03*
X324800Y92340D03*
Y94900D03*
X317400D03*
Y92340D03*
X324800Y97460D03*
X317400D03*
X394199Y36490D03*
Y39050D03*
Y41610D03*
X386799D03*
Y39050D03*
Y36490D03*
X760778Y341984D03*
Y339424D03*
Y336864D03*
X758996Y742442D03*
Y739882D03*
Y737322D03*
X760799Y1146610D03*
Y1144050D03*
Y1141490D03*
X759114Y1954773D03*
Y1952213D03*
Y1949653D03*
X768178Y336864D03*
Y339424D03*
Y341984D03*
X766396Y737322D03*
Y739882D03*
Y742442D03*
X768199Y1141490D03*
Y1144050D03*
Y1146610D03*
X761627Y1548856D03*
Y1546296D03*
Y1543736D03*
X769027D03*
Y1546296D03*
Y1548856D03*
X766514Y1949653D03*
Y1952213D03*
Y1954773D03*
X814700Y270060D03*
Y267500D03*
Y264940D03*
X822100D03*
Y267500D03*
Y270060D03*
X813200Y672660D03*
Y670100D03*
Y667540D03*
X820600D03*
Y670100D03*
Y672660D03*
X812900Y1075460D03*
Y1072900D03*
Y1070340D03*
X820300D03*
Y1072900D03*
Y1075460D03*
X814700Y1483160D03*
Y1480600D03*
Y1478040D03*
X822100D03*
Y1480600D03*
Y1483160D03*
X815300Y1887560D03*
Y1885000D03*
Y1882440D03*
X822700D03*
Y1885000D03*
Y1887560D03*
G54D76*
X854101Y1710351D03*
Y1733149D03*
G54D49*
X116249Y1093990D03*
Y1096550D03*
Y1099110D03*
X109749D03*
Y1093990D03*
X117249Y1720110D03*
Y1717550D03*
Y1714990D03*
X123749D03*
Y1720110D03*
X176999Y490913D03*
Y488353D03*
Y485793D03*
X183499D03*
Y490913D03*
X315248Y339174D03*
Y334054D03*
X316749Y746110D03*
Y740990D03*
X313249Y1554490D03*
Y1559610D03*
X321748Y334054D03*
Y336614D03*
Y339174D03*
X323249Y740990D03*
Y743550D03*
Y746110D03*
X319749Y1554490D03*
Y1557050D03*
Y1559610D03*
X326971Y1944349D03*
Y1946909D03*
Y1949469D03*
X320471D03*
Y1944349D03*
X347749Y67110D03*
Y64550D03*
Y61990D03*
X354249D03*
Y67110D03*
X387749Y50990D03*
X394249D03*
X387749Y56110D03*
Y53550D03*
X394249Y56110D03*
X761228Y323864D03*
Y328984D03*
X760446Y724822D03*
Y729942D03*
X760583Y1131452D03*
Y1126332D03*
X760064Y1942273D03*
Y1937153D03*
X767728Y323864D03*
Y326424D03*
Y328984D03*
X766946Y724822D03*
Y727382D03*
Y729942D03*
X767083Y1126332D03*
Y1128892D03*
Y1131452D03*
X770077Y1531236D03*
X763577D03*
X770077Y1533796D03*
Y1536356D03*
X763577D03*
X766564Y1937153D03*
Y1939713D03*
Y1942273D03*
G54D58*
X140940Y550300D03*
X143500D03*
X146060D03*
Y557700D03*
X143500D03*
X140940D03*
X181340Y937100D03*
X183900D03*
X186460D03*
Y944500D03*
X183900D03*
X181340D03*
X172240Y1678400D03*
X174800D03*
X177360D03*
Y1685800D03*
X174800D03*
X172240D03*
X242040Y275100D03*
X244600D03*
X247160D03*
Y282500D03*
X244600D03*
X242040D03*
X241440Y682500D03*
X244000D03*
X246560D03*
Y689900D03*
X244000D03*
X241440D03*
X315939Y352350D03*
X318499D03*
X321059D03*
Y359750D03*
X318499D03*
X315939D03*
X316939Y759350D03*
X319499D03*
X322059D03*
Y766750D03*
X319499D03*
X316939D03*
X315939Y1569850D03*
X318499D03*
X321059D03*
Y1577250D03*
X318499D03*
X315939D03*
X319080Y1959072D03*
X321640D03*
X324200D03*
Y1966472D03*
X321640D03*
X319080D03*
G54D67*
X242299Y76550D03*
X958299Y89550D03*
G54D77*
X876000Y1703899D03*
X879750D03*
X883500D03*
Y1714499D03*
X879750D03*
X876000D03*
G54D68*
X236699Y76550D03*
X952699Y89550D03*
G54D59*
X144099Y1247113D03*
X170899D03*
X179100Y461000D03*
X205900D03*
X203099Y859613D03*
X229899D03*
G54D69*
X238149Y102050D03*
G54D78*
X1005807Y1636102D03*
Y1631102D03*
Y1626102D03*
Y1621102D03*
Y1661102D03*
Y1656102D03*
Y1651102D03*
Y1646102D03*
Y1641102D03*
Y1676102D03*
Y1671102D03*
Y1666102D03*
G54D79*
G01X-78740Y15000D02*
G03X-63740Y0I15000J0D01*
G01X-78740Y15000D02*
Y319646D01*
G01X-63740Y334646D02*
G03X-78740Y319646I0J-15000D01*
G01Y908315D02*
G03X-63740Y893315I15000J0D01*
G01X-78740Y908315D02*
Y1304286D01*
G01X-63740Y1319286D02*
G03X-78740Y1304286I0J-15000D01*
G01Y1892953D02*
G03X-63740Y1877953I15000J0D01*
G01X-78740Y1892953D02*
Y1977126D01*
G01X-63740Y1992126D02*
G03X-78740Y1977126I0J-15000D01*
G01X-7874Y0D02*
X-63740D01*
G01X-7874Y334646D02*
X-63740D01*
G01X-7874Y893315D02*
X-63740D01*
G01X-7874Y1319286D02*
X-63740D01*
G01X-7874Y1877953D02*
X-63740D01*
G01X-7874Y1992126D02*
X-63740D01*
G01X-7874Y17253D02*
Y0D01*
G01X0Y17214D02*
G03X-7874I-3937J0D01*
G01Y41772D02*
Y167110D01*
G01Y41772D02*
G03X0I3937J0D01*
G01Y167110D02*
G03X-7874I-3937J0D01*
G01Y191667D02*
Y308383D01*
G01Y191667D02*
G03X0I3937J0D01*
G01Y308383D02*
G03X-7874I-3937J0D01*
G01Y331986D02*
Y334646D01*
G01Y332003D02*
G03X0I3937J0D01*
G01X-7874Y905988D02*
Y893315D01*
G01X0Y905988D02*
G03X-7874I-3937J0D01*
G01Y1106301D02*
Y933234D01*
G01D02*
G03X0I3937J0D01*
G01Y1106301D02*
G03X-7874I-3937J0D01*
G01Y1280567D02*
Y1129921D01*
G01D02*
G03X0I3937J0D01*
G01Y1280567D02*
G03X-7874I-3937J0D01*
G01Y1309889D02*
Y1319286D01*
G01Y1309889D02*
G03X0I3937J0D01*
G01X-7874Y1889223D02*
Y1877953D01*
G01X0Y1889223D02*
G03X-7874I-3937J0D01*
G01X0D02*
G03X-7874I-3937J0D01*
G01Y1912843D02*
Y1962927D01*
G01Y1912843D02*
G03X0I3937J0D01*
G01Y1962927D02*
G03X-7874I-3937J0D01*
G01X0D02*
G03X-7874I-3937J0D01*
G01Y1986547D02*
Y1992126D01*
G01Y1986547D02*
G03X0I3937J0D01*
G01X3937Y0D02*
X1029528D01*
G01X0Y3937D02*
G03X3937Y0I3937J0D01*
G01X0Y409646D02*
Y3937D01*
G01X3937Y413583D02*
X0Y409646D01*
G01X19882Y413583D02*
X3937D01*
G01Y421063D02*
X19882D01*
G01X0Y425000D02*
X3937Y421063D01*
G01X0Y819094D02*
Y425000D01*
G01X3937Y823031D02*
X0Y819094D01*
G01X19882Y823031D02*
X3937D01*
G01Y830512D02*
X19882D01*
G01X0Y834449D02*
X3937Y830512D01*
G01X0Y1393898D02*
Y834449D01*
G01X3937Y1397835D02*
X0Y1393898D01*
G01X19882Y1397835D02*
X3937D01*
G01Y1405315D02*
X19882D01*
G01X0Y1409252D02*
X3937Y1405315D01*
G01X0Y1803346D02*
Y1409252D01*
G01X3937Y1807283D02*
X0Y1803346D01*
G01X19882Y1807283D02*
X3937D01*
G01Y1814764D02*
X19882D01*
G01X0Y1818701D02*
X3937Y1814764D01*
G01X0Y1988189D02*
Y1818701D01*
G01X3937Y1992126D02*
G03X0Y1988189I0J-3937D01*
G01X1029528Y1992126D02*
X3937D01*
G01X19882Y413583D02*
G03Y421063I0J3740D01*
G01Y823031D02*
G03Y830512I0J3741D01*
G01Y1397835D02*
G03Y1405315I0J3740D01*
G01Y1807283D02*
G03Y1814764I0J3740D01*
G01X989744Y1616083D02*
X1015354D01*
G01X989744D02*
G03Y1611870I0J-2107D01*
G01X1015354D02*
X989744D01*
G01X1033465Y3937D02*
Y1424882D01*
G01X1029528Y0D02*
G03X1033465Y3937I0J3937D01*
G01X1041338Y24677D02*
G03X1033464I-3937J0D01*
G01X1041338D02*
G03X1033464I-3937J0D01*
G01Y48297D02*
G03X1041338I3937J0D01*
G01Y217343D02*
G03X1033464I-3937J0D01*
G01X1041338D02*
G03X1033464I-3937J0D01*
G01Y240964D02*
G03X1041338I3937J0D01*
G01X1033464D02*
G03X1041338I3937J0D01*
G01Y445039D02*
G03X1033464I-3937J0D01*
G01X1041338D02*
G03X1033464I-3937J0D01*
G01Y468659D02*
G03X1041338I3937J0D01*
G01X1033464D02*
G03X1041338I3937J0D01*
G01Y697473D02*
G03X1033464I-3937J0D01*
G01X1041338D02*
G03X1033464I-3937J0D01*
G01Y721093D02*
G03X1041338I3937J0D01*
G01X1033464D02*
G03X1041338I3937J0D01*
G01Y996852D02*
G03X1033464I-3937J0D01*
G01X1041338D02*
G03X1033464I-3937J0D01*
G01Y1020472D02*
G03X1041338I3937J0D01*
G01X1033464D02*
G03X1041338I3937J0D01*
G01Y1344060D02*
G03X1033464I-3937J0D01*
G01X1041338D02*
G03X1033464I-3937J0D01*
G01Y1367680D02*
G03X1041338I3937J0D01*
G01X1033464D02*
G03X1041338I3937J0D01*
G01X1033465Y1424882D02*
X1029528Y1428819D01*
G01X1019291Y1433740D02*
Y1607933D01*
G01Y1433740D02*
G03X1024213Y1428819I4921J0D01*
G01X1029528D02*
X1024213D01*
G01X1015354Y1616083D02*
X1019291Y1620020D01*
G01Y1607933D02*
X1015354Y1611870D01*
G01X1019291Y1620020D02*
Y1676496D01*
G01X1029528Y1681417D02*
X1033465Y1685354D01*
G01X1024213Y1681417D02*
G03X1019291Y1676496I-1J-4921D01*
G01X1033465Y1685354D02*
Y1988189D01*
G01X1024213Y1681417D02*
X1029528D01*
G01X1041338Y1739719D02*
G03X1033464I-3937J0D01*
G01X1041338D02*
G03X1033464I-3937J0D01*
G01Y1763339D02*
G03X1041338I3937J0D01*
G01X1033464D02*
G03X1041338I3937J0D01*
G01Y1959242D02*
G03X1033464I-3937J0D01*
G01X1041338D02*
G03X1033464I-3937J0D01*
G01X1033465Y1988189D02*
G03X1029528Y1992126I-3937J0D01*
G01X1033464Y1982862D02*
G03X1041338I3937J0D01*
G01Y24677D02*
Y0D01*
G01D02*
X1097205D01*
G01X1041338Y217343D02*
Y48297D01*
G01Y445039D02*
Y240964D01*
G01Y697473D02*
Y468601D01*
G01Y996852D02*
Y721093D01*
G01Y1344060D02*
Y1020472D01*
G01Y1367680D02*
Y1393701D01*
G01D02*
X1097205D01*
G01X1041338Y1733129D02*
Y1716536D01*
G01X1065043D02*
X1041338D01*
G01Y1739719D02*
Y1731536D01*
G01Y1959242D02*
Y1763310D01*
G01Y1992126D02*
X1097205D01*
G01X1041338Y1982862D02*
Y1992126D01*
G01X1056338Y1716536D02*
X1097205D01*
G01Y0D02*
G03X1112205Y15000I0J15000D01*
G01Y1378701D02*
G03X1097205Y1393701I-15000J0D01*
G01Y1716536D02*
G03X1112205Y1731536I0J15000D01*
G01Y1977126D02*
G03X1097205Y1992126I-15000J0D01*
G01X1112205Y648419D02*
Y15000D01*
G01Y656293D02*
G03Y648419I0J-3937D01*
G01Y1378701D02*
Y656293D01*
G01Y1977126D02*
Y1731536D01*
M02*
